FILE_TYPE = MACRO_DRAWING;
SET COLOR_WIRE YELLOW;
SET COLOR_PROP ORANGE;
SET COLOR_DOT WHITE;
SET COLOR_ARC YELLOW;
SET COLOR_BODY GREEN;
SET COLOR_NOTE PURPLE;
SET PROP_DISPLAY VALUE;
SET PAGE_NUMBER P378;
FORCEADD TCA9548APWR..1
(-4900 4575);
FORCEPROP 1 LAST LOCATION U6020
J 0
(-5100 5155);
DISPLAY 0.723404 (-5100 5155);
PAINT GREEN (-5100 5155);
FORCEPROP 0 LAST $SEC 1
J 0
(-5100 5300);
DISPLAY 0.680851 (-5100 5300);
PAINT MONO (-5100 5300);
DISPLAY INVISIBLE (-5100 5300);
FORCEPROP 0 LAST CDS_SEC 1
J 0
(-5100 5300);
DISPLAY 0.680851 (-5100 5300);
DISPLAY INVISIBLE (-5100 5300);
FORCEPROP 0 LASTPIN (-5250 4900) $PN 1
J 2
(-5260 4910);
DISPLAY 0.680851 (-5260 4910);
PAINT MONO (-5260 4910);
FORCEPROP 0 LASTPIN (-5250 4850) $PN 2
J 2
(-5260 4860);
DISPLAY 0.680851 (-5260 4860);
PAINT MONO (-5260 4860);
FORCEPROP 0 LASTPIN (-5250 4800) $PN 21
J 2
(-5260 4810);
DISPLAY 0.680851 (-5260 4810);
PAINT MONO (-5260 4810);
FORCEPROP 0 LASTPIN (-4550 4150) $PN 12
J 0
(-4540 4160);
DISPLAY 0.680851 (-4540 4160);
PAINT MONO (-4540 4160);
FORCEPROP 0 LASTPIN (-5250 4700) $PN 3
J 2
(-5260 4710);
DISPLAY 0.680851 (-5260 4710);
PAINT MONO (-5260 4710);
FORCEPROP 0 LASTPIN (-5250 4550) $PN 5
J 2
(-5260 4560);
DISPLAY 0.680851 (-5260 4560);
PAINT MONO (-5260 4560);
FORCEPROP 0 LASTPIN (-5250 4450) $PN 7
J 2
(-5260 4460);
DISPLAY 0.680851 (-5260 4460);
PAINT MONO (-5260 4460);
FORCEPROP 0 LASTPIN (-5250 4350) $PN 9
J 2
(-5260 4360);
DISPLAY 0.680851 (-5260 4360);
PAINT MONO (-5260 4360);
FORCEPROP 0 LASTPIN (-5250 4250) $PN 11
J 2
(-5260 4260);
DISPLAY 0.680851 (-5260 4260);
PAINT MONO (-5260 4260);
FORCEPROP 0 LASTPIN (-4550 4550) $PN 14
J 0
(-4540 4560);
DISPLAY 0.680851 (-4540 4560);
PAINT MONO (-4540 4560);
FORCEPROP 0 LASTPIN (-4550 4450) $PN 16
J 0
(-4540 4460);
DISPLAY 0.680851 (-4540 4460);
PAINT MONO (-4540 4460);
FORCEPROP 0 LASTPIN (-4550 4350) $PN 18
J 0
(-4540 4360);
DISPLAY 0.680851 (-4540 4360);
PAINT MONO (-4540 4360);
FORCEPROP 0 LASTPIN (-4550 4250) $PN 20
J 0
(-4540 4260);
DISPLAY 0.680851 (-4540 4260);
PAINT MONO (-4540 4260);
FORCEPROP 0 LASTPIN (-4550 4800) $PN 22
J 0
(-4540 4810);
DISPLAY 0.680851 (-4540 4810);
PAINT MONO (-4540 4810);
FORCEPROP 0 LASTPIN (-5250 4600) $PN 4
J 2
(-5260 4610);
DISPLAY 0.680851 (-5260 4610);
PAINT MONO (-5260 4610);
FORCEPROP 0 LASTPIN (-5250 4500) $PN 6
J 2
(-5260 4510);
DISPLAY 0.680851 (-5260 4510);
PAINT MONO (-5260 4510);
FORCEPROP 0 LASTPIN (-5250 4400) $PN 8
J 2
(-5260 4410);
DISPLAY 0.680851 (-5260 4410);
PAINT MONO (-5260 4410);
FORCEPROP 0 LASTPIN (-5250 4300) $PN 10
J 2
(-5260 4310);
DISPLAY 0.680851 (-5260 4310);
PAINT MONO (-5260 4310);
FORCEPROP 0 LASTPIN (-4550 4600) $PN 13
J 0
(-4540 4610);
DISPLAY 0.680851 (-4540 4610);
PAINT MONO (-4540 4610);
FORCEPROP 0 LASTPIN (-4550 4500) $PN 15
J 0
(-4540 4510);
DISPLAY 0.680851 (-4540 4510);
PAINT MONO (-4540 4510);
FORCEPROP 0 LASTPIN (-4550 4400) $PN 17
J 0
(-4540 4410);
DISPLAY 0.680851 (-4540 4410);
PAINT MONO (-4540 4410);
FORCEPROP 0 LASTPIN (-4550 4300) $PN 19
J 0
(-4540 4310);
DISPLAY 0.680851 (-4540 4310);
PAINT MONO (-4540 4310);
FORCEPROP 0 LASTPIN (-4550 4850) $PN 23
J 0
(-4540 4860);
DISPLAY 0.680851 (-4540 4860);
PAINT MONO (-4540 4860);
FORCEPROP 0 LASTPIN (-5250 5000) $PN 24
J 2
(-5260 5010);
DISPLAY 0.680851 (-5260 5010);
PAINT MONO (-5260 5010);
FORCEPROP 1 LAST MATERIAL IC
J 0
(-5100 5055);
DISPLAY 0.723404 (-5100 5055);
PAINT GREEN (-5100 5055);
FORCEPROP 2 LAST PART_TYPE SMLF
J 0
(-5100 5250);
DISPLAY 1.021277 (-5100 5250);
FORCEPROP 2 LAST VALUE TCA9548APWR
J 0
(-5100 5200);
DISPLAY 1.021277 (-5100 5200);
FORCEPROP 2 LAST CDS_LIB pure_quanta
J 0
(-4900 4575);
DISPLAY INVISIBLE (-4900 4575);
FORCEPROP 1 LAST CDS_LMAN_SYM_OUTLINE -200,475,200,-475
J 0
(-4900 4575);
DISPLAY 0.468085 (-4900 4575);
PAINT GREEN (-4900 4575);
DISPLAY INVISIBLE (-4900 4575);
FORCEPROP 1 LAST NEEDS_NO_SIZE TRUE
J 0
(-4900 4575);
DISPLAY 0.723404 (-4900 4575);
PAINT GREEN (-4900 4575);
DISPLAY INVISIBLE (-4900 4575);
FORCEPROP 1 LAST PATH I1
J 0
(-4900 4575);
DISPLAY 0.723404 (-4900 4575);
PAINT GREEN (-4900 4575);
DISPLAY INVISIBLE (-4900 4575);
FORCEPROP 1 LAST PART_NUMBER AL009548K02
J 0
(-5100 5102);
DISPLAY 0.723404 (-5100 5102);
PAINT GREEN (-5100 5102);
DISPLAY INVISIBLE (-5100 5102);
FORCEADD OFFPAGE..2
(-775 1450);
FORCEPROP 2 LAST $XR1 321 
J 0
(-466 1450);
DISPLAY 0.638298 (-466 1450);
PAINT MONO (-466 1450);
FORCEPROP 2 LAST $XR0 184 
J 0
(-586 1450);
DISPLAY 0.638298 (-586 1450);
PAINT MONO (-586 1450);
FORCEPROP 2 LAST CDS_LIB standard
J 2
(-775 1450);
DISPLAY INVISIBLE (-775 1450);
FORCEPROP 1 LAST OFFPAGE TRUE
J 0
(-450 1325);
DISPLAY 0.872340 (-450 1325);
PAINT GREEN (-450 1325);
DISPLAY INVISIBLE (-450 1325);
FORCEPROP 1 LAST COMMENT_BODY TRUE
J 0
(-820 1355);
DISPLAY 0.872340 (-820 1355);
PAINT GREEN (-820 1355);
DISPLAY INVISIBLE (-820 1355);
FORCEPROP 2 LAST PATH I10
J 2
(-825 1525);
DISPLAY 0.680851 (-825 1525);
DISPLAY INVISIBLE (-825 1525);
FORCEADD Q_RES..2
(-8300 1800);
FORCEPROP 1 LAST LOCATION R6771
J 0
(-8255 1925);
DISPLAY 0.787234 (-8255 1925);
FORCEPROP 0 LAST $SEC 1
J 0
(-8250 1975);
DISPLAY 0.680851 (-8250 1975);
PAINT MONO (-8250 1975);
DISPLAY INVISIBLE (-8250 1975);
FORCEPROP 0 LAST CDS_SEC 1
J 0
(-8250 1975);
DISPLAY 0.680851 (-8250 1975);
DISPLAY INVISIBLE (-8250 1975);
FORCEPROP 1 LASTPIN (-8300 1900) $PN 1
J 0
(-8295 1862);
DISPLAY 0.787234 (-8295 1862);
PAINT MONO (-8295 1862);
FORCEPROP 1 LASTPIN (-8300 1700) $PN 2
J 0
(-8295 1710);
DISPLAY 0.787234 (-8295 1710);
PAINT MONO (-8295 1710);
FORCEPROP 1 LAST PACK_TYPE 0201LF
J 0
(-8250 1650);
DISPLAY 0.787234 (-8250 1650);
FORCEPROP 1 LAST MATERIAL EMPTY
J 0
(-8260 1725);
DISPLAY 0.787234 (-8260 1725);
FORCEPROP 1 LAST WATTAGE 1/20W
J 0
(-8260 1775);
DISPLAY 0.787234 (-8260 1775);
FORCEPROP 1 LAST VALUE 4.7K
J 0
(-8255 1875);
DISPLAY 0.787234 (-8255 1875);
FORCEPROP 1 LAST TOLERANCE 5%
J 0
(-8255 1825);
DISPLAY 0.787234 (-8255 1825);
FORCEPROP 2 LAST CDS_LIB pure_quanta
J 0
(-8300 1800);
DISPLAY INVISIBLE (-8300 1800);
FORCEPROP 1 LAST PATH I100
J 0
(-8250 1975);
DISPLAY 0.978723 (-8250 1975);
PAINT WHITE (-8250 1975);
DISPLAY INVISIBLE (-8250 1975);
FORCEPROP 1 LAST PART_NUMBER CS24701JE04
J 0
(-8260 1675);
DISPLAY 0.978723 (-8260 1675);
DISPLAY INVISIBLE (-8260 1675);
FORCEADD OFFPAGE..5
R 2
(-7050 1475);
FORCEPROP 2 LAST $XR0 184 
J 0
(-6861 1475);
DISPLAY 0.638298 (-6861 1475);
PAINT MONO (-6861 1475);
FORCEPROP 2 LAST CDS_LIB standard
J 0
(-7050 1475);
DISPLAY INVISIBLE (-7050 1475);
FORCEPROP 1 LAST OFFPAGE TRUE
J 2
(-7375 1350);
DISPLAY 0.872340 (-7375 1350);
PAINT GREEN (-7375 1350);
DISPLAY INVISIBLE (-7375 1350);
FORCEPROP 1 LAST COMMENT_BODY TRUE
J 2
(-7150 1400);
DISPLAY 0.872340 (-7150 1400);
PAINT GREEN (-7150 1400);
DISPLAY INVISIBLE (-7150 1400);
FORCEPROP 2 LAST PATH I101
J 0
(-6850 1525);
DISPLAY 0.680851 (-6850 1525);
DISPLAY INVISIBLE (-6850 1525);
FORCEADD OFFPAGE..5
R 2
(-7050 1375);
FORCEPROP 2 LAST $XR0 184 
J 0
(-6861 1375);
DISPLAY 0.638298 (-6861 1375);
PAINT MONO (-6861 1375);
FORCEPROP 2 LAST CDS_LIB standard
J 0
(-7050 1375);
DISPLAY INVISIBLE (-7050 1375);
FORCEPROP 1 LAST OFFPAGE TRUE
J 2
(-7375 1250);
DISPLAY 0.872340 (-7375 1250);
PAINT GREEN (-7375 1250);
DISPLAY INVISIBLE (-7375 1250);
FORCEPROP 1 LAST COMMENT_BODY TRUE
J 2
(-7150 1300);
DISPLAY 0.872340 (-7150 1300);
PAINT GREEN (-7150 1300);
DISPLAY INVISIBLE (-7150 1300);
FORCEPROP 2 LAST PATH I102
J 0
(-6850 1425);
DISPLAY 0.680851 (-6850 1425);
DISPLAY INVISIBLE (-6850 1425);
FORCEADD OFFPAGE..5
R 2
(-7050 1275);
FORCEPROP 2 LAST $XR0 184 
J 0
(-6861 1275);
DISPLAY 0.638298 (-6861 1275);
PAINT MONO (-6861 1275);
FORCEPROP 2 LAST CDS_LIB standard
J 0
(-7050 1275);
DISPLAY INVISIBLE (-7050 1275);
FORCEPROP 1 LAST OFFPAGE TRUE
J 2
(-7375 1150);
DISPLAY 0.872340 (-7375 1150);
PAINT GREEN (-7375 1150);
DISPLAY INVISIBLE (-7375 1150);
FORCEPROP 1 LAST COMMENT_BODY TRUE
J 2
(-7150 1200);
DISPLAY 0.872340 (-7150 1200);
PAINT GREEN (-7150 1200);
DISPLAY INVISIBLE (-7150 1200);
FORCEPROP 2 LAST PATH I103
J 0
(-6850 1325);
DISPLAY 0.680851 (-6850 1325);
DISPLAY INVISIBLE (-6850 1325);
FORCEADD Q_RES..1
(-6700 4700);
FORCEPROP 1 LAST LOCATION R6776
J 0
(-6550 4700);
DISPLAY 0.638298 (-6550 4700);
PAINT SKYBLUE (-6550 4700);
FORCEPROP 0 LAST $SEC 1
J 0
(-6550 4750);
DISPLAY 0.680851 (-6550 4750);
PAINT MONO (-6550 4750);
DISPLAY INVISIBLE (-6550 4750);
FORCEPROP 0 LAST CDS_SEC 1
J 0
(-6550 4750);
DISPLAY 0.680851 (-6550 4750);
DISPLAY INVISIBLE (-6550 4750);
FORCEPROP 1 LASTPIN (-6800 4700) $PN 1
J 0
(-6788 4712);
DISPLAY 0.787234 (-6788 4712);
PAINT MONO (-6788 4712);
FORCEPROP 1 LASTPIN (-6600 4700) $PN 2
J 0
(-6638 4712);
DISPLAY 0.787234 (-6638 4712);
PAINT MONO (-6638 4712);
FORCEPROP 1 LAST TOLERANCE 5%
J 0
(-6925 4700);
DISPLAY 0.510638 (-6925 4700);
FORCEPROP 1 LAST VALUE 0
J 2
(-6825 4700);
DISPLAY 0.510638 (-6825 4700);
FORCEPROP 1 LAST PACK_TYPE 0201LF
J 0
(-7200 4700);
DISPLAY 0.510638 (-7200 4700);
FORCEPROP 1 LAST MATERIAL CHIP
J 0
(-7050 4700);
DISPLAY 0.510638 (-7050 4700);
FORCEPROP 1 LAST WATTAGE 1/20W
J 2
(-6900 4775);
DISPLAY 0.510638 (-6900 4775);
DISPLAY INVISIBLE (-6900 4775);
FORCEPROP 2 LAST CDS_LIB pure_quanta
J 0
(-6700 4700);
DISPLAY INVISIBLE (-6700 4700);
FORCEPROP 1 LAST PATH I104
J 0
(-6750 4850);
DISPLAY 0.978723 (-6750 4850);
PAINT WHITE (-6750 4850);
DISPLAY INVISIBLE (-6750 4850);
FORCEPROP 1 LAST PART_NUMBER CS00001JE10
J 0
(-6750 4825);
DISPLAY 0.510638 (-6750 4825);
DISPLAY INVISIBLE (-6750 4825);
FORCEADD OFFPAGE..1
(-8200 4700);
FORCEPROP 2 LAST $XR1 184 
J 0
(-8541 4700);
DISPLAY 0.638298 (-8541 4700);
PAINT MONO (-8541 4700);
FORCEPROP 2 LAST $XR0 81 
J 0
(-8421 4700);
DISPLAY 0.638298 (-8421 4700);
PAINT MONO (-8421 4700);
FORCEPROP 2 LAST CDS_LIB standard
J 0
(-8200 4700);
DISPLAY INVISIBLE (-8200 4700);
FORCEPROP 1 LAST OFFPAGE TRUE
J 0
(-7875 4575);
DISPLAY 1.170213 (-7875 4575);
PAINT GREEN (-7875 4575);
DISPLAY INVISIBLE (-7875 4575);
FORCEPROP 1 LAST COMMENT_BODY TRUE
J 0
(-8075 4600);
DISPLAY 1.170213 (-8075 4600);
PAINT GREEN (-8075 4600);
DISPLAY INVISIBLE (-8075 4600);
FORCEPROP 2 LAST PATH I105
J 0
(-8150 4775);
DISPLAY 0.680851 (-8150 4775);
DISPLAY INVISIBLE (-8150 4775);
FORCEADD OFFPAGE..1
(-8000 3275);
FORCEPROP 2 LAST $XR1 184 
J 0
(-8341 3275);
DISPLAY 0.638298 (-8341 3275);
PAINT MONO (-8341 3275);
FORCEPROP 2 LAST $XR0 81 
J 0
(-8221 3275);
DISPLAY 0.638298 (-8221 3275);
PAINT MONO (-8221 3275);
FORCEPROP 2 LAST CDS_LIB standard
J 0
(-8000 3275);
DISPLAY INVISIBLE (-8000 3275);
FORCEPROP 1 LAST OFFPAGE TRUE
J 0
(-7675 3150);
DISPLAY 1.170213 (-7675 3150);
PAINT GREEN (-7675 3150);
DISPLAY INVISIBLE (-7675 3150);
FORCEPROP 1 LAST COMMENT_BODY TRUE
J 0
(-7875 3175);
DISPLAY 1.170213 (-7875 3175);
PAINT GREEN (-7875 3175);
DISPLAY INVISIBLE (-7875 3175);
FORCEPROP 2 LAST PATH I106
J 0
(-7950 3350);
DISPLAY 0.680851 (-7950 3350);
DISPLAY INVISIBLE (-7950 3350);
FORCEADD Q_RES..2
(-6975 3000);
FORCEPROP 1 LAST LOCATION R6778
J 0
(-6930 3125);
DISPLAY 0.978723 (-6930 3125);
FORCEPROP 0 LAST $SEC 1
J 0
(-6925 3175);
DISPLAY 0.680851 (-6925 3175);
PAINT MONO (-6925 3175);
DISPLAY INVISIBLE (-6925 3175);
FORCEPROP 0 LAST CDS_SEC 1
J 0
(-6925 3175);
DISPLAY 0.680851 (-6925 3175);
DISPLAY INVISIBLE (-6925 3175);
FORCEPROP 1 LASTPIN (-6975 3100) $PN 1
J 0
(-6970 3062);
DISPLAY 0.787234 (-6970 3062);
PAINT MONO (-6970 3062);
FORCEPROP 1 LASTPIN (-6975 2900) $PN 2
J 0
(-6970 2910);
DISPLAY 0.787234 (-6970 2910);
PAINT MONO (-6970 2910);
FORCEPROP 1 LAST VALUE 10K
J 0
(-6930 3075);
DISPLAY 0.978723 (-6930 3075);
FORCEPROP 1 LAST MATERIAL CHIP
J 0
(-6935 2925);
DISPLAY 0.978723 (-6935 2925);
FORCEPROP 1 LAST WATTAGE 1/20W
J 0
(-6935 2975);
DISPLAY 0.978723 (-6935 2975);
FORCEPROP 1 LAST TOLERANCE 1%
J 0
(-6930 3025);
DISPLAY 0.978723 (-6930 3025);
FORCEPROP 1 LAST PACK_TYPE 0201LF
J 0
(-6935 2825);
DISPLAY 0.978723 (-6935 2825);
FORCEPROP 2 LAST CDS_LIB pure_quanta
J 0
(-6975 3000);
DISPLAY INVISIBLE (-6975 3000);
FORCEPROP 1 LAST PATH I107
J 0
(-6925 3175);
DISPLAY 0.978723 (-6925 3175);
PAINT WHITE (-6925 3175);
DISPLAY INVISIBLE (-6925 3175);
FORCEPROP 1 LAST PART_NUMBER CS31001FE17
J 0
(-6935 2875);
DISPLAY 0.978723 (-6935 2875);
DISPLAY INVISIBLE (-6935 2875);
FORCEADD UNIVERSAL_GND..1
(-6975 2325);
FORCEPROP 3 LASTPIN (-6975 2375) SIG_NAME GND\g
J 0
(-6965 2385);
DISPLAY 0.659574 (-6965 2385);
PAINT MONO (-6965 2385);
DISPLAY INVISIBLE (-6965 2385);
FORCEPROP 2 LAST CDS_LIB pure_quanta_power
J 0
(-6975 2325);
DISPLAY INVISIBLE (-6975 2325);
FORCEPROP 1 LAST HDL_POWER GND
J 1
(-6950 2250);
DISPLAY 0.872340 (-6950 2250);
PAINT GREEN (-6950 2250);
DISPLAY INVISIBLE (-6950 2250);
FORCEPROP 1 LAST PATH I108
J 0
(-6900 2325);
DISPLAY 0.872340 (-6900 2325);
PAINT AQUA (-6900 2325);
DISPLAY INVISIBLE (-6900 2325);
FORCEADD Q_RES..1
(-2625 1350);
FORCEPROP 1 LAST LOCATION R6719
J 0
(-2925 1350);
DISPLAY 0.978723 (-2925 1350);
PAINT SKYBLUE (-2925 1350);
FORCEPROP 0 LAST $SEC 1
J 0
(-2100 1400);
DISPLAY 0.680851 (-2100 1400);
PAINT MONO (-2100 1400);
DISPLAY INVISIBLE (-2100 1400);
FORCEPROP 0 LAST CDS_SEC 1
J 0
(-2100 1400);
DISPLAY 0.680851 (-2100 1400);
DISPLAY INVISIBLE (-2100 1400);
FORCEPROP 1 LASTPIN (-2725 1350) $PN 1
J 0
(-2713 1362);
DISPLAY 0.787234 (-2713 1362);
PAINT MONO (-2713 1362);
FORCEPROP 1 LASTPIN (-2525 1350) $PN 2
J 0
(-2563 1362);
DISPLAY 0.787234 (-2563 1362);
PAINT MONO (-2563 1362);
FORCEPROP 1 LAST VALUE 1K
J 2
(-2350 1350);
DISPLAY 0.978723 (-2350 1350);
FORCEPROP 1 LAST MATERIAL CHIP
J 0
(-2325 1350);
DISPLAY 0.978723 (-2325 1350);
FORCEPROP 1 LAST PACK_TYPE 0201LF
J 0
(-2100 1350);
DISPLAY 0.978723 (-2100 1350);
FORCEPROP 1 LAST TOLERANCE 1%
J 0
(-2650 1550);
DISPLAY 0.978723 (-2650 1550);
DISPLAY INVISIBLE (-2650 1550);
FORCEPROP 1 LAST WATTAGE 1/20W
J 2
(-2250 1550);
DISPLAY 0.978723 (-2250 1550);
DISPLAY INVISIBLE (-2250 1550);
FORCEPROP 2 LAST CDS_LIB pure_quanta
J 0
(-2625 1350);
DISPLAY INVISIBLE (-2625 1350);
FORCEPROP 1 LAST PATH I11
J 0
(-2675 1500);
DISPLAY 0.978723 (-2675 1500);
PAINT WHITE (-2675 1500);
DISPLAY INVISIBLE (-2675 1500);
FORCEPROP 1 LAST PART_NUMBER CS21001FE07
J 0
(-2675 1450);
DISPLAY 0.978723 (-2675 1450);
DISPLAY INVISIBLE (-2675 1450);
FORCEADD OFFPAGE..3
(-1725 4850);
FORCEPROP 2 LAST $XR0 151 
J 0
(-1511 4850);
DISPLAY 0.638298 (-1511 4850);
PAINT MONO (-1511 4850);
FORCEPROP 2 LAST CDS_LIB standard
J 0
(-1725 4850);
DISPLAY INVISIBLE (-1725 4850);
FORCEPROP 1 LAST OFFPAGE TRUE
J 0
(-1400 4725);
DISPLAY 0.872340 (-1400 4725);
PAINT GREEN (-1400 4725);
DISPLAY INVISIBLE (-1400 4725);
FORCEPROP 1 LAST COMMENT_BODY TRUE
J 0
(-1775 4750);
DISPLAY 0.872340 (-1775 4750);
PAINT GREEN (-1775 4750);
DISPLAY INVISIBLE (-1775 4750);
FORCEPROP 2 LAST PATH I111
J 0
(-1525 4925);
DISPLAY 0.680851 (-1525 4925);
DISPLAY INVISIBLE (-1525 4925);
FORCEADD OFFPAGE..1
R 2
(-1725 4800);
FORCEPROP 2 LAST $XR0 151 
J 0
(-1509 4800);
DISPLAY 0.638298 (-1509 4800);
PAINT MONO (-1509 4800);
FORCEPROP 2 LAST CDS_LIB standard
J 2
(-1725 4800);
DISPLAY INVISIBLE (-1725 4800);
FORCEPROP 1 LAST OFFPAGE TRUE
J 2
(-2050 4675);
DISPLAY 1.170213 (-2050 4675);
PAINT GREEN (-2050 4675);
DISPLAY INVISIBLE (-2050 4675);
FORCEPROP 1 LAST COMMENT_BODY TRUE
J 2
(-1850 4700);
DISPLAY 1.170213 (-1850 4700);
PAINT GREEN (-1850 4700);
DISPLAY INVISIBLE (-1850 4700);
FORCEPROP 2 LAST PATH I112
J 2
(-1775 4875);
DISPLAY 0.680851 (-1775 4875);
DISPLAY INVISIBLE (-1775 4875);
FORCEADD P1V0_AUX..1
(-8600 2225);
FORCEPROP 3 LASTPIN (-8600 2175) SIG_NAME P1V8_AUX\g
J 0
(-8590 2185);
DISPLAY 0.659574 (-8590 2185);
PAINT MONO (-8590 2185);
DISPLAY INVISIBLE (-8590 2185);
FORCEPROP 1 LAST HDL_POWER P1V8_AUX
J 1
(-8590 2265);
DISPLAY 0.489362 (-8590 2265);
PAINT GREEN (-8590 2265);
FORCEPROP 2 LAST CDS_LIB pure_quanta_power
J 0
(-8600 2225);
DISPLAY INVISIBLE (-8600 2225);
FORCEPROP 1 LAST PATH I113
J 0
(-8550 2250);
DISPLAY 0.872340 (-8550 2250);
PAINT AQUA (-8550 2250);
DISPLAY INVISIBLE (-8550 2250);
FORCEADD UNIVERSAL_GND..1
(-1225 5225);
FORCEPROP 3 LASTPIN (-1225 5275) SIG_NAME GND\g
J 0
(-1215 5285);
DISPLAY 0.659574 (-1215 5285);
PAINT MONO (-1215 5285);
DISPLAY INVISIBLE (-1215 5285);
FORCEPROP 2 LAST CDS_LIB pure_quanta_power
J 0
(-1225 5225);
DISPLAY INVISIBLE (-1225 5225);
FORCEPROP 1 LAST HDL_POWER GND
J 1
(-1200 5150);
DISPLAY 0.872340 (-1200 5150);
PAINT GREEN (-1200 5150);
DISPLAY INVISIBLE (-1200 5150);
FORCEPROP 1 LAST PATH I115
J 0
(-1150 5225);
DISPLAY 0.872340 (-1150 5225);
PAINT AQUA (-1150 5225);
DISPLAY INVISIBLE (-1150 5225);
FORCEADD CONN3_210HP1030BR1..1
(-800 5450);
FORCEPROP 1 LAST LOCATION JP6500
J 0
(-725 5425);
DISPLAY 0.723404 (-725 5425);
FORCEPROP 0 LAST $SEC 1
J 0
(-750 5575);
DISPLAY 0.680851 (-750 5575);
PAINT MONO (-750 5575);
DISPLAY INVISIBLE (-750 5575);
FORCEPROP 0 LAST CDS_SEC 1
J 0
(-750 5575);
DISPLAY 0.680851 (-750 5575);
DISPLAY INVISIBLE (-750 5575);
FORCEPROP 0 LASTPIN (-1000 5500) $PN 1
J 2
(-1010 5510);
DISPLAY 0.680851 (-1010 5510);
PAINT MONO (-1010 5510);
FORCEPROP 0 LASTPIN (-1000 5450) $PN 2
J 2
(-1010 5460);
DISPLAY 0.680851 (-1010 5460);
PAINT MONO (-1010 5460);
FORCEPROP 0 LASTPIN (-1000 5400) $PN 3
J 2
(-1010 5410);
DISPLAY 0.680851 (-1010 5410);
PAINT MONO (-1010 5410);
FORCEPROP 2 LAST PART_TYPE THLF
J 0
(-750 5475);
DISPLAY 1.021277 (-750 5475);
FORCEPROP 1 LAST MATERIAL IO
J 0
(-725 5324);
DISPLAY 0.723404 (-725 5324);
FORCEPROP 2 LAST VALUE CONN3_210-HP1-030BR1
J 0
(-750 5525);
DISPLAY 0.723404 (-750 5525);
FORCEPROP 2 LAST CDS_LIB pure_quanta
J 2
(-800 5450);
DISPLAY INVISIBLE (-800 5450);
FORCEPROP 1 LAST CDS_LMAN_SYM_OUTLINE -50,100,50,-100
J 0
(-800 5450);
DISPLAY 0.468085 (-800 5450);
PAINT GREEN (-800 5450);
DISPLAY INVISIBLE (-800 5450);
FORCEPROP 1 LAST NEEDS_NO_SIZE TRUE
J 0
(-800 5450);
DISPLAY 0.723404 (-800 5450);
PAINT GREEN (-800 5450);
DISPLAY INVISIBLE (-800 5450);
FORCEPROP 1 LAST PATH I116
J 0
(-800 5450);
DISPLAY 0.723404 (-800 5450);
PAINT GREEN (-800 5450);
DISPLAY INVISIBLE (-800 5450);
FORCEPROP 1 LAST PART_NUMBER DFHD03MS213
J 0
(-725 5375);
DISPLAY 0.723404 (-725 5375);
DISPLAY INVISIBLE (-725 5375);
FORCEADD Q_RES..1
(-2150 5450);
FORCEPROP 1 LAST LOCATION R1515
J 0
(-2000 5450);
DISPLAY 0.638298 (-2000 5450);
PAINT SKYBLUE (-2000 5450);
FORCEPROP 0 LAST $SEC 1
J 0
(-2000 5500);
DISPLAY 0.680851 (-2000 5500);
PAINT MONO (-2000 5500);
DISPLAY INVISIBLE (-2000 5500);
FORCEPROP 0 LAST CDS_SEC 1
J 0
(-2000 5500);
DISPLAY 0.680851 (-2000 5500);
DISPLAY INVISIBLE (-2000 5500);
FORCEPROP 1 LASTPIN (-2250 5450) $PN 1
J 0
(-2238 5462);
DISPLAY 0.787234 (-2238 5462);
PAINT MONO (-2238 5462);
FORCEPROP 1 LASTPIN (-2050 5450) $PN 2
J 0
(-2088 5462);
DISPLAY 0.787234 (-2088 5462);
PAINT MONO (-2088 5462);
FORCEPROP 1 LAST TOLERANCE 5%
J 0
(-2375 5450);
DISPLAY 0.510638 (-2375 5450);
FORCEPROP 1 LAST MATERIAL CHIP
J 0
(-2500 5450);
DISPLAY 0.510638 (-2500 5450);
FORCEPROP 1 LAST PACK_TYPE 0201LF
J 0
(-2650 5450);
DISPLAY 0.510638 (-2650 5450);
FORCEPROP 1 LAST VALUE 0
J 2
(-2275 5450);
DISPLAY 0.510638 (-2275 5450);
FORCEPROP 2 LAST CDS_LIB pure_quanta
J 0
(-2150 5450);
DISPLAY INVISIBLE (-2150 5450);
FORCEPROP 1 LAST WATTAGE 1/20W
J 2
(-2350 5525);
DISPLAY 0.510638 (-2350 5525);
DISPLAY INVISIBLE (-2350 5525);
FORCEPROP 1 LAST PATH I117
J 0
(-2200 5600);
DISPLAY 0.978723 (-2200 5600);
PAINT WHITE (-2200 5600);
DISPLAY INVISIBLE (-2200 5600);
FORCEPROP 1 LAST PART_NUMBER CS00001JE10
J 0
(-2200 5575);
DISPLAY 0.510638 (-2200 5575);
DISPLAY INVISIBLE (-2200 5575);
FORCEADD Q_RES..1
(-2150 5500);
FORCEPROP 1 LAST LOCATION R1514
J 0
(-2000 5500);
DISPLAY 0.638298 (-2000 5500);
PAINT SKYBLUE (-2000 5500);
FORCEPROP 0 LAST $SEC 1
J 0
(-2000 5550);
DISPLAY 0.680851 (-2000 5550);
PAINT MONO (-2000 5550);
DISPLAY INVISIBLE (-2000 5550);
FORCEPROP 0 LAST CDS_SEC 1
J 0
(-2000 5550);
DISPLAY 0.680851 (-2000 5550);
DISPLAY INVISIBLE (-2000 5550);
FORCEPROP 1 LASTPIN (-2250 5500) $PN 1
J 0
(-2238 5512);
DISPLAY 0.787234 (-2238 5512);
PAINT MONO (-2238 5512);
FORCEPROP 1 LASTPIN (-2050 5500) $PN 2
J 0
(-2088 5512);
DISPLAY 0.787234 (-2088 5512);
PAINT MONO (-2088 5512);
FORCEPROP 1 LAST VALUE 0
J 2
(-2275 5500);
DISPLAY 0.510638 (-2275 5500);
FORCEPROP 1 LAST PACK_TYPE 0201LF
J 0
(-2650 5500);
DISPLAY 0.510638 (-2650 5500);
FORCEPROP 1 LAST MATERIAL CHIP
J 0
(-2500 5500);
DISPLAY 0.510638 (-2500 5500);
FORCEPROP 1 LAST TOLERANCE 5%
J 0
(-2375 5500);
DISPLAY 0.510638 (-2375 5500);
FORCEPROP 2 LAST CDS_LIB pure_quanta
J 0
(-2150 5500);
DISPLAY INVISIBLE (-2150 5500);
FORCEPROP 1 LAST WATTAGE 1/20W
J 2
(-2350 5575);
DISPLAY 0.510638 (-2350 5575);
DISPLAY INVISIBLE (-2350 5575);
FORCEPROP 1 LAST PATH I118
J 0
(-2200 5650);
DISPLAY 0.978723 (-2200 5650);
PAINT WHITE (-2200 5650);
DISPLAY INVISIBLE (-2200 5650);
FORCEPROP 1 LAST PART_NUMBER CS00001JE10
J 0
(-2200 5625);
DISPLAY 0.510638 (-2200 5625);
DISPLAY INVISIBLE (-2200 5625);
FORCEADD Q_RES..1
(-3050 4850);
FORCEPROP 1 LAST LOCATION R6779
J 0
(-2900 4850);
DISPLAY 0.638298 (-2900 4850);
FORCEPROP 2 LAST SEC 1
J 0
(-3100 5050);
DISPLAY 0.680851 (-3100 5050);
PAINT MONO (-3100 5050);
DISPLAY INVISIBLE (-3100 5050);
FORCEPROP 1 LASTPIN (-3150 4850) $PN 1
J 0
(-3138 4862);
DISPLAY 0.787234 (-3138 4862);
PAINT MONO (-3138 4862);
FORCEPROP 1 LASTPIN (-2950 4850) $PN 2
J 0
(-2988 4862);
DISPLAY 0.787234 (-2988 4862);
PAINT MONO (-2988 4862);
FORCEPROP 1 LAST VALUE 33.2
J 2
(-3175 4850);
DISPLAY 0.510638 (-3175 4850);
FORCEPROP 1 LAST TOLERANCE 1%
J 0
(-3325 4850);
DISPLAY 0.510638 (-3325 4850);
FORCEPROP 1 LAST MATERIAL CHIP
J 0
(-3450 4850);
DISPLAY 0.510638 (-3450 4850);
FORCEPROP 1 LAST PACK_TYPE 0201LF
J 0
(-3625 4850);
DISPLAY 0.510638 (-3625 4850);
FORCEPROP 2 LAST CDS_LIB pure_quanta
J 0
(-3050 4850);
DISPLAY INVISIBLE (-3050 4850);
FORCEPROP 2 LAST SEC_TYPE 0201LF
J 0
(-3100 5050);
DISPLAY 0.680851 (-3100 5050);
DISPLAY INVISIBLE (-3100 5050);
FORCEPROP 1 LAST WATTAGE 1/20W
J 2
(-3075 4700);
DISPLAY 0.978723 (-3075 4700);
DISPLAY INVISIBLE (-3075 4700);
FORCEPROP 1 LAST PATH I119
J 0
(-3100 5000);
DISPLAY 0.978723 (-3100 5000);
PAINT WHITE (-3100 5000);
DISPLAY INVISIBLE (-3100 5000);
FORCEPROP 1 LAST PART_NUMBER CS03321FE09
J 0
(-3250 4925);
DISPLAY 0.638298 (-3250 4925);
DISPLAY INVISIBLE (-3250 4925);
FORCEADD OFFPAGE..2
(-775 1350);
FORCEPROP 2 LAST $XR1 321 
J 0
(-466 1350);
DISPLAY 0.638298 (-466 1350);
PAINT MONO (-466 1350);
FORCEPROP 2 LAST $XR0 184 
J 0
(-586 1350);
DISPLAY 0.638298 (-586 1350);
PAINT MONO (-586 1350);
FORCEPROP 2 LAST CDS_LIB standard
J 0
(-775 1350);
DISPLAY INVISIBLE (-775 1350);
FORCEPROP 1 LAST OFFPAGE TRUE
J 0
(-450 1225);
DISPLAY 0.872340 (-450 1225);
PAINT GREEN (-450 1225);
DISPLAY INVISIBLE (-450 1225);
FORCEPROP 1 LAST COMMENT_BODY TRUE
J 0
(-820 1255);
DISPLAY 0.872340 (-820 1255);
PAINT GREEN (-820 1255);
DISPLAY INVISIBLE (-820 1255);
FORCEPROP 2 LAST PATH I12
J 0
(-600 1425);
DISPLAY 0.680851 (-600 1425);
DISPLAY INVISIBLE (-600 1425);
FORCEADD Q_RES..1
(-3050 4800);
FORCEPROP 1 LAST LOCATION R6780
J 0
(-2900 4800);
DISPLAY 0.638298 (-2900 4800);
FORCEPROP 2 LAST SEC 1
J 0
(-3100 5000);
DISPLAY 0.680851 (-3100 5000);
PAINT MONO (-3100 5000);
DISPLAY INVISIBLE (-3100 5000);
FORCEPROP 1 LASTPIN (-3150 4800) $PN 1
J 0
(-3138 4812);
DISPLAY 0.787234 (-3138 4812);
PAINT MONO (-3138 4812);
FORCEPROP 1 LASTPIN (-2950 4800) $PN 2
J 0
(-2988 4812);
DISPLAY 0.787234 (-2988 4812);
PAINT MONO (-2988 4812);
FORCEPROP 1 LAST VALUE 33.2
J 2
(-3175 4800);
DISPLAY 0.510638 (-3175 4800);
FORCEPROP 1 LAST TOLERANCE 1%
J 0
(-3325 4800);
DISPLAY 0.510638 (-3325 4800);
FORCEPROP 1 LAST MATERIAL CHIP
J 0
(-3450 4800);
DISPLAY 0.510638 (-3450 4800);
FORCEPROP 1 LAST PACK_TYPE 0201LF
J 0
(-3625 4800);
DISPLAY 0.510638 (-3625 4800);
FORCEPROP 1 LAST WATTAGE 1/20W
J 2
(-3075 4650);
DISPLAY 0.978723 (-3075 4650);
DISPLAY INVISIBLE (-3075 4650);
FORCEPROP 2 LAST CDS_LIB pure_quanta
J 0
(-3050 4800);
DISPLAY INVISIBLE (-3050 4800);
FORCEPROP 2 LAST SEC_TYPE 0201LF
J 0
(-3100 5000);
DISPLAY 0.680851 (-3100 5000);
DISPLAY INVISIBLE (-3100 5000);
FORCEPROP 1 LAST PATH I120
J 0
(-3100 4950);
DISPLAY 0.978723 (-3100 4950);
PAINT WHITE (-3100 4950);
DISPLAY INVISIBLE (-3100 4950);
FORCEPROP 1 LAST PART_NUMBER CS03321FE09
J 0
(-3250 4875);
DISPLAY 0.638298 (-3250 4875);
DISPLAY INVISIBLE (-3250 4875);
FORCEADD Q_RES..1
(-6350 4500);
FORCEPROP 1 LAST LOCATION R6736
J 0
(-6200 4500);
DISPLAY 0.638298 (-6200 4500);
PAINT SKYBLUE (-6200 4500);
FORCEPROP 0 LAST $SEC 1
J 0
(-6200 4550);
DISPLAY 0.680851 (-6200 4550);
PAINT MONO (-6200 4550);
DISPLAY INVISIBLE (-6200 4550);
FORCEPROP 0 LAST CDS_SEC 1
J 0
(-6200 4550);
DISPLAY 0.680851 (-6200 4550);
DISPLAY INVISIBLE (-6200 4550);
FORCEPROP 1 LASTPIN (-6450 4500) $PN 1
J 0
(-6438 4512);
DISPLAY 0.787234 (-6438 4512);
PAINT MONO (-6438 4512);
FORCEPROP 1 LASTPIN (-6250 4500) $PN 2
J 0
(-6288 4512);
DISPLAY 0.787234 (-6288 4512);
PAINT MONO (-6288 4512);
FORCEPROP 1 LAST TOLERANCE 5%
J 0
(-6575 4500);
DISPLAY 0.510638 (-6575 4500);
FORCEPROP 1 LAST MATERIAL CHIP
J 0
(-6700 4500);
DISPLAY 0.510638 (-6700 4500);
FORCEPROP 1 LAST VALUE 0
J 2
(-6475 4500);
DISPLAY 0.510638 (-6475 4500);
FORCEPROP 1 LAST PACK_TYPE 0201LF
J 0
(-6850 4500);
DISPLAY 0.510638 (-6850 4500);
FORCEPROP 2 LAST CDS_LIB pure_quanta
J 0
(-6350 4500);
DISPLAY INVISIBLE (-6350 4500);
FORCEPROP 1 LAST WATTAGE 1/20W
J 2
(-6550 4575);
DISPLAY 0.510638 (-6550 4575);
DISPLAY INVISIBLE (-6550 4575);
FORCEPROP 1 LAST PATH I13
J 0
(-6400 4650);
DISPLAY 0.978723 (-6400 4650);
PAINT WHITE (-6400 4650);
DISPLAY INVISIBLE (-6400 4650);
FORCEPROP 1 LAST PART_NUMBER CS00001JE10
J 0
(-6400 4625);
DISPLAY 0.510638 (-6400 4625);
DISPLAY INVISIBLE (-6400 4625);
FORCEADD Q_RES..1
(-6350 4450);
FORCEPROP 1 LAST LOCATION R6737
J 0
(-6200 4450);
DISPLAY 0.638298 (-6200 4450);
PAINT SKYBLUE (-6200 4450);
FORCEPROP 0 LAST $SEC 1
J 0
(-6200 4500);
DISPLAY 0.680851 (-6200 4500);
PAINT MONO (-6200 4500);
DISPLAY INVISIBLE (-6200 4500);
FORCEPROP 0 LAST CDS_SEC 1
J 0
(-6200 4500);
DISPLAY 0.680851 (-6200 4500);
DISPLAY INVISIBLE (-6200 4500);
FORCEPROP 1 LASTPIN (-6450 4450) $PN 1
J 0
(-6438 4462);
DISPLAY 0.787234 (-6438 4462);
PAINT MONO (-6438 4462);
FORCEPROP 1 LASTPIN (-6250 4450) $PN 2
J 0
(-6288 4462);
DISPLAY 0.787234 (-6288 4462);
PAINT MONO (-6288 4462);
FORCEPROP 1 LAST VALUE 0
J 2
(-6475 4450);
DISPLAY 0.510638 (-6475 4450);
FORCEPROP 1 LAST TOLERANCE 5%
J 0
(-6575 4450);
DISPLAY 0.510638 (-6575 4450);
FORCEPROP 1 LAST MATERIAL CHIP
J 0
(-6700 4450);
DISPLAY 0.510638 (-6700 4450);
FORCEPROP 1 LAST PACK_TYPE 0201LF
J 0
(-6850 4450);
DISPLAY 0.510638 (-6850 4450);
FORCEPROP 2 LAST CDS_LIB pure_quanta
J 0
(-6350 4450);
DISPLAY INVISIBLE (-6350 4450);
FORCEPROP 1 LAST WATTAGE 1/20W
J 2
(-6550 4525);
DISPLAY 0.510638 (-6550 4525);
DISPLAY INVISIBLE (-6550 4525);
FORCEPROP 1 LAST PATH I14
J 0
(-6400 4600);
DISPLAY 0.978723 (-6400 4600);
PAINT WHITE (-6400 4600);
DISPLAY INVISIBLE (-6400 4600);
FORCEPROP 1 LAST PART_NUMBER CS00001JE10
J 0
(-6400 4575);
DISPLAY 0.510638 (-6400 4575);
DISPLAY INVISIBLE (-6400 4575);
FORCEADD OFFPAGE..3
R 2
(-7725 4500);
FORCEPROP 2 LAST $XR1 332 
J 0
(-8155 4500);
DISPLAY 0.638298 (-8155 4500);
PAINT MONO (-8155 4500);
FORCEPROP 2 LAST $XR0 184 
J 0
(-8035 4500);
DISPLAY 0.638298 (-8035 4500);
PAINT MONO (-8035 4500);
FORCEPROP 2 LAST CDS_LIB standard
J 0
(-7725 4500);
DISPLAY INVISIBLE (-7725 4500);
FORCEPROP 1 LAST OFFPAGE TRUE
J 2
(-8050 4375);
DISPLAY 0.872340 (-8050 4375);
PAINT GREEN (-8050 4375);
DISPLAY INVISIBLE (-8050 4375);
FORCEPROP 1 LAST COMMENT_BODY TRUE
J 2
(-7675 4400);
DISPLAY 0.872340 (-7675 4400);
PAINT GREEN (-7675 4400);
DISPLAY INVISIBLE (-7675 4400);
FORCEPROP 2 LAST PATH I15
J 0
(-7675 4575);
DISPLAY 0.680851 (-7675 4575);
DISPLAY INVISIBLE (-7675 4575);
FORCEADD OFFPAGE..2
R 2
(-7750 4450);
FORCEPROP 2 LAST $XR1 332 
J 0
(-8155 4450);
DISPLAY 0.638298 (-8155 4450);
PAINT MONO (-8155 4450);
FORCEPROP 2 LAST $XR0 184 
J 0
(-8035 4450);
DISPLAY 0.638298 (-8035 4450);
PAINT MONO (-8035 4450);
FORCEPROP 2 LAST CDS_LIB standard
J 0
(-7750 4450);
DISPLAY INVISIBLE (-7750 4450);
FORCEPROP 1 LAST OFFPAGE TRUE
J 2
(-8075 4325);
DISPLAY 0.872340 (-8075 4325);
PAINT GREEN (-8075 4325);
DISPLAY INVISIBLE (-8075 4325);
FORCEPROP 1 LAST COMMENT_BODY TRUE
J 2
(-7705 4355);
DISPLAY 0.872340 (-7705 4355);
PAINT GREEN (-7705 4355);
DISPLAY INVISIBLE (-7705 4355);
FORCEPROP 2 LAST PATH I16
J 0
(-7700 4525);
DISPLAY 0.680851 (-7700 4525);
DISPLAY INVISIBLE (-7700 4525);
FORCEADD Q_RES..1
(-2625 1275);
FORCEPROP 1 LAST LOCATION R6738
J 0
(-2925 1275);
DISPLAY 0.978723 (-2925 1275);
PAINT SKYBLUE (-2925 1275);
FORCEPROP 0 LAST $SEC 1
J 0
(-2100 1325);
DISPLAY 0.680851 (-2100 1325);
PAINT MONO (-2100 1325);
DISPLAY INVISIBLE (-2100 1325);
FORCEPROP 0 LAST CDS_SEC 1
J 0
(-2100 1325);
DISPLAY 0.680851 (-2100 1325);
DISPLAY INVISIBLE (-2100 1325);
FORCEPROP 1 LASTPIN (-2725 1275) $PN 1
J 0
(-2713 1287);
DISPLAY 0.787234 (-2713 1287);
PAINT MONO (-2713 1287);
FORCEPROP 1 LASTPIN (-2525 1275) $PN 2
J 0
(-2563 1287);
DISPLAY 0.787234 (-2563 1287);
PAINT MONO (-2563 1287);
FORCEPROP 1 LAST VALUE 1K
J 2
(-2350 1275);
DISPLAY 0.978723 (-2350 1275);
FORCEPROP 1 LAST PACK_TYPE 0201LF
J 0
(-2100 1275);
DISPLAY 0.978723 (-2100 1275);
FORCEPROP 1 LAST MATERIAL CHIP
J 0
(-2325 1275);
DISPLAY 0.978723 (-2325 1275);
FORCEPROP 2 LAST CDS_LIB pure_quanta
J 0
(-2625 1275);
DISPLAY INVISIBLE (-2625 1275);
FORCEPROP 1 LAST WATTAGE 1/20W
J 2
(-2250 1475);
DISPLAY 0.978723 (-2250 1475);
DISPLAY INVISIBLE (-2250 1475);
FORCEPROP 1 LAST TOLERANCE 1%
J 0
(-2650 1475);
DISPLAY 0.978723 (-2650 1475);
DISPLAY INVISIBLE (-2650 1475);
FORCEPROP 1 LAST PATH I17
J 0
(-2675 1425);
DISPLAY 0.978723 (-2675 1425);
PAINT WHITE (-2675 1425);
DISPLAY INVISIBLE (-2675 1425);
FORCEPROP 1 LAST PART_NUMBER CS21001FE07
J 0
(-2675 1375);
DISPLAY 0.978723 (-2675 1375);
DISPLAY INVISIBLE (-2675 1375);
FORCEADD Q_RES..1
(-2625 1200);
FORCEPROP 1 LAST LOCATION R6739
J 0
(-2925 1200);
DISPLAY 0.978723 (-2925 1200);
PAINT SKYBLUE (-2925 1200);
FORCEPROP 0 LAST $SEC 1
J 0
(-2100 1250);
DISPLAY 0.680851 (-2100 1250);
PAINT MONO (-2100 1250);
DISPLAY INVISIBLE (-2100 1250);
FORCEPROP 0 LAST CDS_SEC 1
J 0
(-2100 1250);
DISPLAY 0.680851 (-2100 1250);
DISPLAY INVISIBLE (-2100 1250);
FORCEPROP 1 LASTPIN (-2725 1200) $PN 1
J 0
(-2713 1212);
DISPLAY 0.787234 (-2713 1212);
PAINT MONO (-2713 1212);
FORCEPROP 1 LASTPIN (-2525 1200) $PN 2
J 0
(-2563 1212);
DISPLAY 0.787234 (-2563 1212);
PAINT MONO (-2563 1212);
FORCEPROP 1 LAST MATERIAL CHIP
J 0
(-2325 1200);
DISPLAY 0.978723 (-2325 1200);
FORCEPROP 1 LAST VALUE 1K
J 2
(-2350 1200);
DISPLAY 0.978723 (-2350 1200);
FORCEPROP 1 LAST PACK_TYPE 0201LF
J 0
(-2100 1200);
DISPLAY 0.978723 (-2100 1200);
FORCEPROP 2 LAST CDS_LIB pure_quanta
J 0
(-2625 1200);
DISPLAY INVISIBLE (-2625 1200);
FORCEPROP 1 LAST TOLERANCE 1%
J 0
(-2650 1400);
DISPLAY 0.978723 (-2650 1400);
DISPLAY INVISIBLE (-2650 1400);
FORCEPROP 1 LAST WATTAGE 1/20W
J 2
(-2250 1400);
DISPLAY 0.978723 (-2250 1400);
DISPLAY INVISIBLE (-2250 1400);
FORCEPROP 1 LAST PATH I18
J 0
(-2675 1350);
DISPLAY 0.978723 (-2675 1350);
PAINT WHITE (-2675 1350);
DISPLAY INVISIBLE (-2675 1350);
FORCEPROP 1 LAST PART_NUMBER CS21001FE07
J 0
(-2675 1300);
DISPLAY 0.978723 (-2675 1300);
DISPLAY INVISIBLE (-2675 1300);
FORCEADD OFFPAGE..2
(-775 1275);
FORCEPROP 2 LAST $XR1 332 
J 0
(-466 1275);
DISPLAY 0.638298 (-466 1275);
PAINT MONO (-466 1275);
FORCEPROP 2 LAST $XR0 184 
J 0
(-586 1275);
DISPLAY 0.638298 (-586 1275);
PAINT MONO (-586 1275);
FORCEPROP 2 LAST CDS_LIB standard
J 0
(-775 1275);
DISPLAY INVISIBLE (-775 1275);
FORCEPROP 1 LAST OFFPAGE TRUE
J 0
(-450 1150);
DISPLAY 0.872340 (-450 1150);
PAINT GREEN (-450 1150);
DISPLAY INVISIBLE (-450 1150);
FORCEPROP 1 LAST COMMENT_BODY TRUE
J 0
(-820 1180);
DISPLAY 0.872340 (-820 1180);
PAINT GREEN (-820 1180);
DISPLAY INVISIBLE (-820 1180);
FORCEPROP 2 LAST PATH I19
J 0
(-600 1350);
DISPLAY 0.680851 (-600 1350);
DISPLAY INVISIBLE (-600 1350);
FORCEADD OFFPAGE..2
(-775 1200);
FORCEPROP 2 LAST $XR1 332 
J 0
(-466 1200);
DISPLAY 0.638298 (-466 1200);
PAINT MONO (-466 1200);
FORCEPROP 2 LAST $XR0 184 
J 0
(-586 1200);
DISPLAY 0.638298 (-586 1200);
PAINT MONO (-586 1200);
FORCEPROP 2 LAST CDS_LIB standard
J 0
(-775 1200);
DISPLAY INVISIBLE (-775 1200);
FORCEPROP 1 LAST OFFPAGE TRUE
J 0
(-450 1075);
DISPLAY 0.872340 (-450 1075);
PAINT GREEN (-450 1075);
DISPLAY INVISIBLE (-450 1075);
FORCEPROP 1 LAST COMMENT_BODY TRUE
J 0
(-820 1105);
DISPLAY 0.872340 (-820 1105);
PAINT GREEN (-820 1105);
DISPLAY INVISIBLE (-820 1105);
FORCEPROP 2 LAST PATH I20
J 0
(-600 1275);
DISPLAY 0.680851 (-600 1275);
DISPLAY INVISIBLE (-600 1275);
FORCEADD Q_RES..1
(-6350 4350);
FORCEPROP 1 LAST LOCATION R6747
J 0
(-6200 4350);
DISPLAY 0.638298 (-6200 4350);
PAINT SKYBLUE (-6200 4350);
FORCEPROP 0 LAST $SEC 1
J 0
(-6200 4400);
DISPLAY 0.680851 (-6200 4400);
PAINT MONO (-6200 4400);
DISPLAY INVISIBLE (-6200 4400);
FORCEPROP 0 LAST CDS_SEC 1
J 0
(-6200 4400);
DISPLAY 0.680851 (-6200 4400);
DISPLAY INVISIBLE (-6200 4400);
FORCEPROP 1 LASTPIN (-6450 4350) $PN 1
J 0
(-6438 4362);
DISPLAY 0.787234 (-6438 4362);
PAINT MONO (-6438 4362);
FORCEPROP 1 LASTPIN (-6250 4350) $PN 2
J 0
(-6288 4362);
DISPLAY 0.787234 (-6288 4362);
PAINT MONO (-6288 4362);
FORCEPROP 1 LAST TOLERANCE 5%
J 0
(-6575 4350);
DISPLAY 0.510638 (-6575 4350);
FORCEPROP 1 LAST MATERIAL CHIP
J 0
(-6700 4350);
DISPLAY 0.510638 (-6700 4350);
FORCEPROP 1 LAST VALUE 0
J 2
(-6475 4350);
DISPLAY 0.510638 (-6475 4350);
FORCEPROP 1 LAST PACK_TYPE 0201LF
J 0
(-6850 4350);
DISPLAY 0.510638 (-6850 4350);
FORCEPROP 2 LAST CDS_LIB pure_quanta
J 0
(-6350 4350);
DISPLAY INVISIBLE (-6350 4350);
FORCEPROP 1 LAST WATTAGE 1/20W
J 2
(-6550 4425);
DISPLAY 0.510638 (-6550 4425);
DISPLAY INVISIBLE (-6550 4425);
FORCEPROP 1 LAST PATH I21
J 0
(-6400 4500);
DISPLAY 0.978723 (-6400 4500);
PAINT WHITE (-6400 4500);
DISPLAY INVISIBLE (-6400 4500);
FORCEPROP 1 LAST PART_NUMBER CS00001JE10
J 0
(-6400 4475);
DISPLAY 0.510638 (-6400 4475);
DISPLAY INVISIBLE (-6400 4475);
FORCEADD Q_RES..1
(-6350 4400);
FORCEPROP 1 LAST LOCATION R6746
J 0
(-6200 4400);
DISPLAY 0.638298 (-6200 4400);
PAINT SKYBLUE (-6200 4400);
FORCEPROP 0 LAST $SEC 1
J 0
(-6200 4450);
DISPLAY 0.680851 (-6200 4450);
PAINT MONO (-6200 4450);
DISPLAY INVISIBLE (-6200 4450);
FORCEPROP 0 LAST CDS_SEC 1
J 0
(-6200 4450);
DISPLAY 0.680851 (-6200 4450);
DISPLAY INVISIBLE (-6200 4450);
FORCEPROP 1 LASTPIN (-6450 4400) $PN 1
J 0
(-6438 4412);
DISPLAY 0.787234 (-6438 4412);
PAINT MONO (-6438 4412);
FORCEPROP 1 LASTPIN (-6250 4400) $PN 2
J 0
(-6288 4412);
DISPLAY 0.787234 (-6288 4412);
PAINT MONO (-6288 4412);
FORCEPROP 1 LAST VALUE 0
J 2
(-6475 4400);
DISPLAY 0.510638 (-6475 4400);
FORCEPROP 1 LAST TOLERANCE 5%
J 0
(-6575 4400);
DISPLAY 0.510638 (-6575 4400);
FORCEPROP 1 LAST MATERIAL CHIP
J 0
(-6700 4400);
DISPLAY 0.510638 (-6700 4400);
FORCEPROP 1 LAST PACK_TYPE 0201LF
J 0
(-6850 4400);
DISPLAY 0.510638 (-6850 4400);
FORCEPROP 1 LAST WATTAGE 1/20W
J 2
(-6550 4475);
DISPLAY 0.510638 (-6550 4475);
DISPLAY INVISIBLE (-6550 4475);
FORCEPROP 2 LAST CDS_LIB pure_quanta
J 0
(-6350 4400);
DISPLAY INVISIBLE (-6350 4400);
FORCEPROP 1 LAST PATH I22
J 0
(-6400 4550);
DISPLAY 0.978723 (-6400 4550);
PAINT WHITE (-6400 4550);
DISPLAY INVISIBLE (-6400 4550);
FORCEPROP 1 LAST PART_NUMBER CS00001JE10
J 0
(-6400 4525);
DISPLAY 0.510638 (-6400 4525);
DISPLAY INVISIBLE (-6400 4525);
FORCEADD OFFPAGE..3
R 2
(-7725 4400);
FORCEPROP 2 LAST $XR1 354 
J 0
(-8155 4400);
DISPLAY 0.638298 (-8155 4400);
PAINT MONO (-8155 4400);
FORCEPROP 2 LAST $XR0 184 
J 0
(-8035 4400);
DISPLAY 0.638298 (-8035 4400);
PAINT MONO (-8035 4400);
FORCEPROP 2 LAST CDS_LIB standard
J 0
(-7725 4400);
DISPLAY INVISIBLE (-7725 4400);
FORCEPROP 1 LAST OFFPAGE TRUE
J 2
(-8050 4275);
DISPLAY 0.872340 (-8050 4275);
PAINT GREEN (-8050 4275);
DISPLAY INVISIBLE (-8050 4275);
FORCEPROP 1 LAST COMMENT_BODY TRUE
J 2
(-7675 4300);
DISPLAY 0.872340 (-7675 4300);
PAINT GREEN (-7675 4300);
DISPLAY INVISIBLE (-7675 4300);
FORCEPROP 2 LAST PATH I23
J 0
(-8025 4450);
DISPLAY 0.680851 (-8025 4450);
DISPLAY INVISIBLE (-8025 4450);
FORCEADD OFFPAGE..2
R 2
(-7750 4350);
FORCEPROP 2 LAST $XR1 354 
J 0
(-8155 4350);
DISPLAY 0.638298 (-8155 4350);
PAINT MONO (-8155 4350);
FORCEPROP 2 LAST $XR0 184 
J 0
(-8035 4350);
DISPLAY 0.638298 (-8035 4350);
PAINT MONO (-8035 4350);
FORCEPROP 2 LAST CDS_LIB standard
J 0
(-7750 4350);
DISPLAY INVISIBLE (-7750 4350);
FORCEPROP 1 LAST OFFPAGE TRUE
J 2
(-8075 4225);
DISPLAY 0.872340 (-8075 4225);
PAINT GREEN (-8075 4225);
DISPLAY INVISIBLE (-8075 4225);
FORCEPROP 1 LAST COMMENT_BODY TRUE
J 2
(-7705 4255);
DISPLAY 0.872340 (-7705 4255);
PAINT GREEN (-7705 4255);
DISPLAY INVISIBLE (-7705 4255);
FORCEPROP 2 LAST PATH I24
J 0
(-8025 4400);
DISPLAY 0.680851 (-8025 4400);
DISPLAY INVISIBLE (-8025 4400);
FORCEADD Q_RES..1
(-6350 4250);
FORCEPROP 1 LAST LOCATION R6749
J 0
(-6200 4250);
DISPLAY 0.638298 (-6200 4250);
PAINT SKYBLUE (-6200 4250);
FORCEPROP 0 LAST $SEC 1
J 0
(-6200 4300);
DISPLAY 0.680851 (-6200 4300);
PAINT MONO (-6200 4300);
DISPLAY INVISIBLE (-6200 4300);
FORCEPROP 0 LAST CDS_SEC 1
J 0
(-6200 4300);
DISPLAY 0.680851 (-6200 4300);
DISPLAY INVISIBLE (-6200 4300);
FORCEPROP 1 LASTPIN (-6450 4250) $PN 1
J 0
(-6438 4262);
DISPLAY 0.787234 (-6438 4262);
PAINT MONO (-6438 4262);
FORCEPROP 1 LASTPIN (-6250 4250) $PN 2
J 0
(-6288 4262);
DISPLAY 0.787234 (-6288 4262);
PAINT MONO (-6288 4262);
FORCEPROP 1 LAST VALUE 0
J 2
(-6475 4250);
DISPLAY 0.510638 (-6475 4250);
FORCEPROP 1 LAST TOLERANCE 5%
J 0
(-6575 4250);
DISPLAY 0.510638 (-6575 4250);
FORCEPROP 1 LAST MATERIAL CHIP
J 0
(-6700 4250);
DISPLAY 0.510638 (-6700 4250);
FORCEPROP 1 LAST PACK_TYPE 0201LF
J 0
(-6850 4250);
DISPLAY 0.510638 (-6850 4250);
FORCEPROP 1 LAST WATTAGE 1/20W
J 2
(-6550 4325);
DISPLAY 0.510638 (-6550 4325);
DISPLAY INVISIBLE (-6550 4325);
FORCEPROP 2 LAST CDS_LIB pure_quanta
J 0
(-6350 4250);
DISPLAY INVISIBLE (-6350 4250);
FORCEPROP 1 LAST PATH I25
J 0
(-6400 4400);
DISPLAY 0.978723 (-6400 4400);
PAINT WHITE (-6400 4400);
DISPLAY INVISIBLE (-6400 4400);
FORCEPROP 1 LAST PART_NUMBER CS00001JE10
J 0
(-6400 4375);
DISPLAY 0.510638 (-6400 4375);
DISPLAY INVISIBLE (-6400 4375);
FORCEADD Q_RES..1
(-6350 4300);
FORCEPROP 1 LAST LOCATION R6748
J 0
(-6200 4300);
DISPLAY 0.638298 (-6200 4300);
PAINT SKYBLUE (-6200 4300);
FORCEPROP 0 LAST $SEC 1
J 0
(-6200 4350);
DISPLAY 0.680851 (-6200 4350);
PAINT MONO (-6200 4350);
DISPLAY INVISIBLE (-6200 4350);
FORCEPROP 0 LAST CDS_SEC 1
J 0
(-6200 4350);
DISPLAY 0.680851 (-6200 4350);
DISPLAY INVISIBLE (-6200 4350);
FORCEPROP 1 LASTPIN (-6450 4300) $PN 1
J 0
(-6438 4312);
DISPLAY 0.787234 (-6438 4312);
PAINT MONO (-6438 4312);
FORCEPROP 1 LASTPIN (-6250 4300) $PN 2
J 0
(-6288 4312);
DISPLAY 0.787234 (-6288 4312);
PAINT MONO (-6288 4312);
FORCEPROP 1 LAST VALUE 0
J 2
(-6475 4300);
DISPLAY 0.510638 (-6475 4300);
FORCEPROP 1 LAST MATERIAL CHIP
J 0
(-6700 4300);
DISPLAY 0.510638 (-6700 4300);
FORCEPROP 1 LAST PACK_TYPE 0201LF
J 0
(-6850 4300);
DISPLAY 0.510638 (-6850 4300);
FORCEPROP 1 LAST TOLERANCE 5%
J 0
(-6575 4300);
DISPLAY 0.510638 (-6575 4300);
FORCEPROP 2 LAST CDS_LIB pure_quanta
J 0
(-6350 4300);
DISPLAY INVISIBLE (-6350 4300);
FORCEPROP 1 LAST WATTAGE 1/20W
J 2
(-6550 4375);
DISPLAY 0.510638 (-6550 4375);
DISPLAY INVISIBLE (-6550 4375);
FORCEPROP 1 LAST PATH I26
J 0
(-6400 4450);
DISPLAY 0.978723 (-6400 4450);
PAINT WHITE (-6400 4450);
DISPLAY INVISIBLE (-6400 4450);
FORCEPROP 1 LAST PART_NUMBER CS00001JE10
J 0
(-6400 4425);
DISPLAY 0.510638 (-6400 4425);
DISPLAY INVISIBLE (-6400 4425);
FORCEADD OFFPAGE..3
R 2
(-7725 4300);
FORCEPROP 2 LAST $XR1 343 
J 0
(-8155 4300);
DISPLAY 0.638298 (-8155 4300);
PAINT MONO (-8155 4300);
FORCEPROP 2 LAST $XR0 184 
J 0
(-8035 4300);
DISPLAY 0.638298 (-8035 4300);
PAINT MONO (-8035 4300);
FORCEPROP 2 LAST CDS_LIB standard
J 0
(-7725 4300);
DISPLAY INVISIBLE (-7725 4300);
FORCEPROP 1 LAST OFFPAGE TRUE
J 2
(-8050 4175);
DISPLAY 0.872340 (-8050 4175);
PAINT GREEN (-8050 4175);
DISPLAY INVISIBLE (-8050 4175);
FORCEPROP 1 LAST COMMENT_BODY TRUE
J 2
(-7675 4200);
DISPLAY 0.872340 (-7675 4200);
PAINT GREEN (-7675 4200);
DISPLAY INVISIBLE (-7675 4200);
FORCEPROP 2 LAST PATH I27
J 0
(-8025 4350);
DISPLAY 0.680851 (-8025 4350);
DISPLAY INVISIBLE (-8025 4350);
FORCEADD OFFPAGE..2
R 2
(-7750 4250);
FORCEPROP 2 LAST $XR1 343 
J 0
(-8155 4250);
DISPLAY 0.638298 (-8155 4250);
PAINT MONO (-8155 4250);
FORCEPROP 2 LAST $XR0 184 
J 0
(-8035 4250);
DISPLAY 0.638298 (-8035 4250);
PAINT MONO (-8035 4250);
FORCEPROP 2 LAST CDS_LIB standard
J 0
(-7750 4250);
DISPLAY INVISIBLE (-7750 4250);
FORCEPROP 1 LAST OFFPAGE TRUE
J 2
(-8075 4125);
DISPLAY 0.872340 (-8075 4125);
PAINT GREEN (-8075 4125);
DISPLAY INVISIBLE (-8075 4125);
FORCEPROP 1 LAST COMMENT_BODY TRUE
J 2
(-7705 4155);
DISPLAY 0.872340 (-7705 4155);
PAINT GREEN (-7705 4155);
DISPLAY INVISIBLE (-7705 4155);
FORCEPROP 2 LAST PATH I28
J 0
(-8025 4300);
DISPLAY 0.680851 (-8025 4300);
DISPLAY INVISIBLE (-8025 4300);
FORCEADD OFFPAGE..2
(-775 1100);
FORCEPROP 2 LAST $XR1 354 
J 0
(-466 1100);
DISPLAY 0.638298 (-466 1100);
PAINT MONO (-466 1100);
FORCEPROP 2 LAST $XR0 184 
J 0
(-586 1100);
DISPLAY 0.638298 (-586 1100);
PAINT MONO (-586 1100);
FORCEPROP 2 LAST CDS_LIB standard
J 0
(-775 1100);
DISPLAY INVISIBLE (-775 1100);
FORCEPROP 1 LAST OFFPAGE TRUE
J 0
(-450 975);
DISPLAY 0.872340 (-450 975);
PAINT GREEN (-450 975);
DISPLAY INVISIBLE (-450 975);
FORCEPROP 1 LAST COMMENT_BODY TRUE
J 0
(-820 1005);
DISPLAY 0.872340 (-820 1005);
PAINT GREEN (-820 1005);
DISPLAY INVISIBLE (-820 1005);
FORCEPROP 2 LAST PATH I29
J 0
(-600 1175);
DISPLAY 0.680851 (-600 1175);
DISPLAY INVISIBLE (-600 1175);
FORCEADD OFFPAGE..2
(-775 1025);
FORCEPROP 2 LAST $XR1 354 
J 0
(-466 1025);
DISPLAY 0.638298 (-466 1025);
PAINT MONO (-466 1025);
FORCEPROP 2 LAST $XR0 184 
J 0
(-586 1025);
DISPLAY 0.638298 (-586 1025);
PAINT MONO (-586 1025);
FORCEPROP 2 LAST CDS_LIB standard
J 0
(-775 1025);
DISPLAY INVISIBLE (-775 1025);
FORCEPROP 1 LAST OFFPAGE TRUE
J 0
(-450 900);
DISPLAY 0.872340 (-450 900);
PAINT GREEN (-450 900);
DISPLAY INVISIBLE (-450 900);
FORCEPROP 1 LAST COMMENT_BODY TRUE
J 0
(-820 930);
DISPLAY 0.872340 (-820 930);
PAINT GREEN (-820 930);
DISPLAY INVISIBLE (-820 930);
FORCEPROP 2 LAST PATH I30
J 0
(-600 1100);
DISPLAY 0.680851 (-600 1100);
DISPLAY INVISIBLE (-600 1100);
FORCEADD Q_RES..1
(-2625 1100);
FORCEPROP 1 LAST LOCATION R6750
J 0
(-2925 1100);
DISPLAY 0.978723 (-2925 1100);
PAINT SKYBLUE (-2925 1100);
FORCEPROP 0 LAST $SEC 1
J 0
(-2100 1150);
DISPLAY 0.680851 (-2100 1150);
PAINT MONO (-2100 1150);
DISPLAY INVISIBLE (-2100 1150);
FORCEPROP 0 LAST CDS_SEC 1
J 0
(-2100 1150);
DISPLAY 0.680851 (-2100 1150);
DISPLAY INVISIBLE (-2100 1150);
FORCEPROP 1 LASTPIN (-2725 1100) $PN 1
J 0
(-2713 1112);
DISPLAY 0.787234 (-2713 1112);
PAINT MONO (-2713 1112);
FORCEPROP 1 LASTPIN (-2525 1100) $PN 2
J 0
(-2563 1112);
DISPLAY 0.787234 (-2563 1112);
PAINT MONO (-2563 1112);
FORCEPROP 1 LAST MATERIAL CHIP
J 0
(-2325 1100);
DISPLAY 0.978723 (-2325 1100);
FORCEPROP 1 LAST VALUE 1K
J 2
(-2350 1100);
DISPLAY 0.978723 (-2350 1100);
FORCEPROP 1 LAST PACK_TYPE 0201LF
J 0
(-2100 1100);
DISPLAY 0.978723 (-2100 1100);
FORCEPROP 1 LAST WATTAGE 1/20W
J 2
(-2250 1300);
DISPLAY 0.978723 (-2250 1300);
DISPLAY INVISIBLE (-2250 1300);
FORCEPROP 1 LAST TOLERANCE 1%
J 0
(-2650 1300);
DISPLAY 0.978723 (-2650 1300);
DISPLAY INVISIBLE (-2650 1300);
FORCEPROP 2 LAST CDS_LIB pure_quanta
J 0
(-2625 1100);
DISPLAY INVISIBLE (-2625 1100);
FORCEPROP 1 LAST PATH I31
J 0
(-2675 1250);
DISPLAY 0.978723 (-2675 1250);
PAINT WHITE (-2675 1250);
DISPLAY INVISIBLE (-2675 1250);
FORCEPROP 1 LAST PART_NUMBER CS21001FE07
J 0
(-2675 1200);
DISPLAY 0.978723 (-2675 1200);
DISPLAY INVISIBLE (-2675 1200);
FORCEADD Q_RES..1
(-2625 1025);
FORCEPROP 1 LAST LOCATION R6751
J 0
(-2925 1025);
DISPLAY 0.978723 (-2925 1025);
PAINT SKYBLUE (-2925 1025);
FORCEPROP 0 LAST $SEC 1
J 0
(-2100 1075);
DISPLAY 0.680851 (-2100 1075);
PAINT MONO (-2100 1075);
DISPLAY INVISIBLE (-2100 1075);
FORCEPROP 0 LAST CDS_SEC 1
J 0
(-2100 1075);
DISPLAY 0.680851 (-2100 1075);
DISPLAY INVISIBLE (-2100 1075);
FORCEPROP 1 LASTPIN (-2725 1025) $PN 1
J 0
(-2713 1037);
DISPLAY 0.787234 (-2713 1037);
PAINT MONO (-2713 1037);
FORCEPROP 1 LASTPIN (-2525 1025) $PN 2
J 0
(-2563 1037);
DISPLAY 0.787234 (-2563 1037);
PAINT MONO (-2563 1037);
FORCEPROP 1 LAST MATERIAL CHIP
J 0
(-2325 1025);
DISPLAY 0.978723 (-2325 1025);
FORCEPROP 1 LAST PACK_TYPE 0201LF
J 0
(-2100 1025);
DISPLAY 0.978723 (-2100 1025);
FORCEPROP 1 LAST VALUE 1K
J 2
(-2350 1025);
DISPLAY 0.978723 (-2350 1025);
FORCEPROP 1 LAST TOLERANCE 1%
J 0
(-2650 1225);
DISPLAY 0.978723 (-2650 1225);
DISPLAY INVISIBLE (-2650 1225);
FORCEPROP 1 LAST WATTAGE 1/20W
J 2
(-2250 1225);
DISPLAY 0.978723 (-2250 1225);
DISPLAY INVISIBLE (-2250 1225);
FORCEPROP 2 LAST CDS_LIB pure_quanta
J 0
(-2625 1025);
DISPLAY INVISIBLE (-2625 1025);
FORCEPROP 1 LAST PATH I32
J 0
(-2675 1175);
DISPLAY 0.978723 (-2675 1175);
PAINT WHITE (-2675 1175);
DISPLAY INVISIBLE (-2675 1175);
FORCEPROP 1 LAST PART_NUMBER CS21001FE07
J 0
(-2675 1125);
DISPLAY 0.978723 (-2675 1125);
DISPLAY INVISIBLE (-2675 1125);
FORCEADD OFFPAGE..2
(-775 950);
FORCEPROP 2 LAST $XR1 343 
J 0
(-466 950);
DISPLAY 0.638298 (-466 950);
PAINT MONO (-466 950);
FORCEPROP 2 LAST $XR0 184 
J 0
(-586 950);
DISPLAY 0.638298 (-586 950);
PAINT MONO (-586 950);
FORCEPROP 2 LAST CDS_LIB standard
J 0
(-775 950);
DISPLAY INVISIBLE (-775 950);
FORCEPROP 1 LAST OFFPAGE TRUE
J 0
(-450 825);
DISPLAY 0.872340 (-450 825);
PAINT GREEN (-450 825);
DISPLAY INVISIBLE (-450 825);
FORCEPROP 1 LAST COMMENT_BODY TRUE
J 0
(-820 855);
DISPLAY 0.872340 (-820 855);
PAINT GREEN (-820 855);
DISPLAY INVISIBLE (-820 855);
FORCEPROP 2 LAST PATH I33
J 0
(-600 1025);
DISPLAY 0.680851 (-600 1025);
DISPLAY INVISIBLE (-600 1025);
FORCEADD OFFPAGE..2
(-775 875);
FORCEPROP 2 LAST $XR1 343 
J 0
(-466 875);
DISPLAY 0.638298 (-466 875);
PAINT MONO (-466 875);
FORCEPROP 2 LAST $XR0 184 
J 0
(-586 875);
DISPLAY 0.638298 (-586 875);
PAINT MONO (-586 875);
FORCEPROP 2 LAST CDS_LIB standard
J 0
(-775 875);
DISPLAY INVISIBLE (-775 875);
FORCEPROP 1 LAST OFFPAGE TRUE
J 0
(-450 750);
DISPLAY 0.872340 (-450 750);
PAINT GREEN (-450 750);
DISPLAY INVISIBLE (-450 750);
FORCEPROP 1 LAST COMMENT_BODY TRUE
J 0
(-820 780);
DISPLAY 0.872340 (-820 780);
PAINT GREEN (-820 780);
DISPLAY INVISIBLE (-820 780);
FORCEPROP 2 LAST PATH I34
J 0
(-600 950);
DISPLAY 0.680851 (-600 950);
DISPLAY INVISIBLE (-600 950);
FORCEADD Q_RES..1
(-2625 950);
FORCEPROP 1 LAST LOCATION R6752
J 0
(-2925 950);
DISPLAY 0.978723 (-2925 950);
PAINT SKYBLUE (-2925 950);
FORCEPROP 0 LAST $SEC 1
J 0
(-2100 1000);
DISPLAY 0.680851 (-2100 1000);
PAINT MONO (-2100 1000);
DISPLAY INVISIBLE (-2100 1000);
FORCEPROP 0 LAST CDS_SEC 1
J 0
(-2100 1000);
DISPLAY 0.680851 (-2100 1000);
DISPLAY INVISIBLE (-2100 1000);
FORCEPROP 1 LASTPIN (-2725 950) $PN 1
J 0
(-2713 962);
DISPLAY 0.787234 (-2713 962);
PAINT MONO (-2713 962);
FORCEPROP 1 LASTPIN (-2525 950) $PN 2
J 0
(-2563 962);
DISPLAY 0.787234 (-2563 962);
PAINT MONO (-2563 962);
FORCEPROP 1 LAST MATERIAL CHIP
J 0
(-2325 950);
DISPLAY 0.978723 (-2325 950);
FORCEPROP 1 LAST PACK_TYPE 0201LF
J 0
(-2100 950);
DISPLAY 0.978723 (-2100 950);
FORCEPROP 1 LAST VALUE 1K
J 2
(-2350 950);
DISPLAY 0.978723 (-2350 950);
FORCEPROP 1 LAST WATTAGE 1/20W
J 2
(-2250 1150);
DISPLAY 0.978723 (-2250 1150);
DISPLAY INVISIBLE (-2250 1150);
FORCEPROP 1 LAST TOLERANCE 1%
J 0
(-2650 1150);
DISPLAY 0.978723 (-2650 1150);
DISPLAY INVISIBLE (-2650 1150);
FORCEPROP 2 LAST CDS_LIB pure_quanta
J 0
(-2625 950);
DISPLAY INVISIBLE (-2625 950);
FORCEPROP 1 LAST PATH I35
J 0
(-2675 1100);
DISPLAY 0.978723 (-2675 1100);
PAINT WHITE (-2675 1100);
DISPLAY INVISIBLE (-2675 1100);
FORCEPROP 1 LAST PART_NUMBER CS21001FE07
J 0
(-2675 1050);
DISPLAY 0.978723 (-2675 1050);
DISPLAY INVISIBLE (-2675 1050);
FORCEADD Q_RES..1
(-2625 875);
FORCEPROP 1 LAST LOCATION R6753
J 0
(-2925 875);
DISPLAY 0.978723 (-2925 875);
PAINT SKYBLUE (-2925 875);
FORCEPROP 0 LAST $SEC 1
J 0
(-2100 925);
DISPLAY 0.680851 (-2100 925);
PAINT MONO (-2100 925);
DISPLAY INVISIBLE (-2100 925);
FORCEPROP 0 LAST CDS_SEC 1
J 0
(-2100 925);
DISPLAY 0.680851 (-2100 925);
DISPLAY INVISIBLE (-2100 925);
FORCEPROP 1 LASTPIN (-2725 875) $PN 1
J 0
(-2713 887);
DISPLAY 0.787234 (-2713 887);
PAINT MONO (-2713 887);
FORCEPROP 1 LASTPIN (-2525 875) $PN 2
J 0
(-2563 887);
DISPLAY 0.787234 (-2563 887);
PAINT MONO (-2563 887);
FORCEPROP 1 LAST MATERIAL CHIP
J 0
(-2325 875);
DISPLAY 0.978723 (-2325 875);
FORCEPROP 1 LAST PACK_TYPE 0201LF
J 0
(-2100 875);
DISPLAY 0.978723 (-2100 875);
FORCEPROP 1 LAST VALUE 1K
J 2
(-2350 875);
DISPLAY 0.978723 (-2350 875);
FORCEPROP 1 LAST TOLERANCE 1%
J 0
(-2650 1075);
DISPLAY 0.978723 (-2650 1075);
DISPLAY INVISIBLE (-2650 1075);
FORCEPROP 1 LAST WATTAGE 1/20W
J 2
(-2250 1075);
DISPLAY 0.978723 (-2250 1075);
DISPLAY INVISIBLE (-2250 1075);
FORCEPROP 2 LAST CDS_LIB pure_quanta
J 0
(-2625 875);
DISPLAY INVISIBLE (-2625 875);
FORCEPROP 1 LAST PATH I36
J 0
(-2675 1025);
DISPLAY 0.978723 (-2675 1025);
PAINT WHITE (-2675 1025);
DISPLAY INVISIBLE (-2675 1025);
FORCEPROP 1 LAST PART_NUMBER CS21001FE07
J 0
(-2675 975);
DISPLAY 0.978723 (-2675 975);
DISPLAY INVISIBLE (-2675 975);
FORCEADD OFFPAGE..2
R 2
(-7750 4550);
FORCEPROP 2 LAST $XR1 321 
J 0
(-8155 4550);
DISPLAY 0.638298 (-8155 4550);
PAINT MONO (-8155 4550);
FORCEPROP 2 LAST $XR0 184 
J 0
(-8035 4550);
DISPLAY 0.638298 (-8035 4550);
PAINT MONO (-8035 4550);
FORCEPROP 2 LAST CDS_LIB standard
J 2
(-7750 4550);
DISPLAY INVISIBLE (-7750 4550);
FORCEPROP 1 LAST OFFPAGE TRUE
J 2
(-8075 4425);
DISPLAY 0.872340 (-8075 4425);
PAINT GREEN (-8075 4425);
DISPLAY INVISIBLE (-8075 4425);
FORCEPROP 1 LAST COMMENT_BODY TRUE
J 2
(-7705 4455);
DISPLAY 0.872340 (-7705 4455);
PAINT GREEN (-7705 4455);
DISPLAY INVISIBLE (-7705 4455);
FORCEPROP 2 LAST PATH I4
J 2
(-7925 4625);
DISPLAY 0.680851 (-7925 4625);
DISPLAY INVISIBLE (-7925 4625);
FORCEADD OFFPAGE..3
R 2
(-7725 4600);
FORCEPROP 2 LAST $XR1 321 
J 0
(-8155 4600);
DISPLAY 0.638298 (-8155 4600);
PAINT MONO (-8155 4600);
FORCEPROP 2 LAST $XR0 184 
J 0
(-8035 4600);
DISPLAY 0.638298 (-8035 4600);
PAINT MONO (-8035 4600);
FORCEPROP 2 LAST CDS_LIB standard
J 2
(-7725 4600);
DISPLAY INVISIBLE (-7725 4600);
FORCEPROP 1 LAST OFFPAGE TRUE
J 2
(-8050 4475);
DISPLAY 0.872340 (-8050 4475);
PAINT GREEN (-8050 4475);
DISPLAY INVISIBLE (-8050 4475);
FORCEPROP 1 LAST COMMENT_BODY TRUE
J 2
(-7675 4500);
DISPLAY 0.872340 (-7675 4500);
PAINT GREEN (-7675 4500);
DISPLAY INVISIBLE (-7675 4500);
FORCEPROP 2 LAST PATH I5
J 2
(-7925 4675);
DISPLAY 0.680851 (-7925 4675);
DISPLAY INVISIBLE (-7925 4675);
FORCEADD Q_RES..1
(-3100 4600);
FORCEPROP 1 LAST LOCATION R6754
J 0
(-2950 4600);
DISPLAY 0.638298 (-2950 4600);
FORCEPROP 2 LAST SEC 1
J 0
(-3150 4800);
DISPLAY 0.680851 (-3150 4800);
PAINT MONO (-3150 4800);
DISPLAY INVISIBLE (-3150 4800);
FORCEPROP 1 LASTPIN (-3200 4600) $PN 1
J 0
(-3188 4612);
DISPLAY 0.787234 (-3188 4612);
PAINT MONO (-3188 4612);
FORCEPROP 1 LASTPIN (-3000 4600) $PN 2
J 0
(-3038 4612);
DISPLAY 0.787234 (-3038 4612);
PAINT MONO (-3038 4612);
FORCEPROP 1 LAST VALUE 0
J 2
(-3225 4600);
DISPLAY 0.510638 (-3225 4600);
FORCEPROP 1 LAST TOLERANCE 5%
J 0
(-3325 4600);
DISPLAY 0.510638 (-3325 4600);
FORCEPROP 1 LAST MATERIAL CHIP
J 0
(-3450 4600);
DISPLAY 0.510638 (-3450 4600);
FORCEPROP 1 LAST PACK_TYPE 0201LF
J 0
(-3600 4600);
DISPLAY 0.510638 (-3600 4600);
FORCEPROP 1 LAST WATTAGE 1/20W
J 2
(-3300 4675);
DISPLAY 0.510638 (-3300 4675);
DISPLAY INVISIBLE (-3300 4675);
FORCEPROP 2 LAST SEC_TYPE 0201LF
J 0
(-3150 4800);
DISPLAY 0.680851 (-3150 4800);
DISPLAY INVISIBLE (-3150 4800);
FORCEPROP 2 LAST CDS_LIB pure_quanta
J 0
(-3100 4600);
DISPLAY INVISIBLE (-3100 4600);
FORCEPROP 1 LAST PATH I53
J 0
(-3150 4750);
DISPLAY 0.978723 (-3150 4750);
PAINT WHITE (-3150 4750);
DISPLAY INVISIBLE (-3150 4750);
FORCEPROP 1 LAST PART_NUMBER CS00001JE10
J 0
(-3150 4725);
DISPLAY 0.510638 (-3150 4725);
DISPLAY INVISIBLE (-3150 4725);
FORCEADD Q_RES..1
(-3100 4550);
FORCEPROP 1 LAST LOCATION R6755
J 0
(-2950 4550);
DISPLAY 0.638298 (-2950 4550);
FORCEPROP 2 LAST SEC 1
J 0
(-3150 4750);
DISPLAY 0.680851 (-3150 4750);
PAINT MONO (-3150 4750);
DISPLAY INVISIBLE (-3150 4750);
FORCEPROP 1 LASTPIN (-3200 4550) $PN 1
J 0
(-3188 4562);
DISPLAY 0.787234 (-3188 4562);
PAINT MONO (-3188 4562);
FORCEPROP 1 LASTPIN (-3000 4550) $PN 2
J 0
(-3038 4562);
DISPLAY 0.787234 (-3038 4562);
PAINT MONO (-3038 4562);
FORCEPROP 1 LAST MATERIAL CHIP
J 0
(-3450 4550);
DISPLAY 0.510638 (-3450 4550);
FORCEPROP 1 LAST VALUE 0
J 2
(-3225 4550);
DISPLAY 0.510638 (-3225 4550);
FORCEPROP 1 LAST TOLERANCE 5%
J 0
(-3325 4550);
DISPLAY 0.510638 (-3325 4550);
FORCEPROP 1 LAST PACK_TYPE 0201LF
J 0
(-3600 4550);
DISPLAY 0.510638 (-3600 4550);
FORCEPROP 2 LAST CDS_LIB pure_quanta
J 0
(-3100 4550);
DISPLAY INVISIBLE (-3100 4550);
FORCEPROP 2 LAST SEC_TYPE 0201LF
J 0
(-3150 4750);
DISPLAY 0.680851 (-3150 4750);
DISPLAY INVISIBLE (-3150 4750);
FORCEPROP 1 LAST WATTAGE 1/20W
J 2
(-3300 4625);
DISPLAY 0.510638 (-3300 4625);
DISPLAY INVISIBLE (-3300 4625);
FORCEPROP 1 LAST PATH I54
J 0
(-3150 4700);
DISPLAY 0.978723 (-3150 4700);
PAINT WHITE (-3150 4700);
DISPLAY INVISIBLE (-3150 4700);
FORCEPROP 1 LAST PART_NUMBER CS00001JE10
J 0
(-3150 4675);
DISPLAY 0.510638 (-3150 4675);
DISPLAY INVISIBLE (-3150 4675);
FORCEADD Q_RES..1
(-3100 4400);
FORCEPROP 1 LAST LOCATION R6758
J 0
(-2950 4400);
DISPLAY 0.638298 (-2950 4400);
FORCEPROP 0 LAST $SEC 1
J 0
(-2950 4450);
DISPLAY 0.680851 (-2950 4450);
PAINT MONO (-2950 4450);
DISPLAY INVISIBLE (-2950 4450);
FORCEPROP 0 LAST CDS_SEC 1
J 0
(-2950 4450);
DISPLAY 0.680851 (-2950 4450);
DISPLAY INVISIBLE (-2950 4450);
FORCEPROP 1 LASTPIN (-3200 4400) $PN 1
J 0
(-3188 4412);
DISPLAY 0.787234 (-3188 4412);
PAINT MONO (-3188 4412);
FORCEPROP 1 LASTPIN (-3000 4400) $PN 2
J 0
(-3038 4412);
DISPLAY 0.787234 (-3038 4412);
PAINT MONO (-3038 4412);
FORCEPROP 1 LAST TOLERANCE 5%
J 0
(-3325 4400);
DISPLAY 0.510638 (-3325 4400);
FORCEPROP 1 LAST VALUE 0
J 2
(-3225 4400);
DISPLAY 0.510638 (-3225 4400);
FORCEPROP 1 LAST MATERIAL CHIP
J 0
(-3450 4400);
DISPLAY 0.510638 (-3450 4400);
FORCEPROP 1 LAST PACK_TYPE 0201LF
J 0
(-3600 4400);
DISPLAY 0.510638 (-3600 4400);
FORCEPROP 2 LAST CDS_LIB pure_quanta
J 0
(-3100 4400);
DISPLAY INVISIBLE (-3100 4400);
FORCEPROP 1 LAST WATTAGE 1/20W
J 2
(-3300 4475);
DISPLAY 0.510638 (-3300 4475);
DISPLAY INVISIBLE (-3300 4475);
FORCEPROP 1 LAST PATH I55
J 0
(-3150 4550);
DISPLAY 0.978723 (-3150 4550);
PAINT WHITE (-3150 4550);
DISPLAY INVISIBLE (-3150 4550);
FORCEPROP 1 LAST PART_NUMBER CS00001JE10
J 0
(-3150 4525);
DISPLAY 0.510638 (-3150 4525);
DISPLAY INVISIBLE (-3150 4525);
FORCEADD Q_RES..1
(-3100 4500);
FORCEPROP 1 LAST LOCATION R6756
J 0
(-2950 4500);
DISPLAY 0.638298 (-2950 4500);
FORCEPROP 0 LAST $SEC 1
J 0
(-2950 4550);
DISPLAY 0.680851 (-2950 4550);
PAINT MONO (-2950 4550);
DISPLAY INVISIBLE (-2950 4550);
FORCEPROP 0 LAST CDS_SEC 1
J 0
(-2950 4550);
DISPLAY 0.680851 (-2950 4550);
DISPLAY INVISIBLE (-2950 4550);
FORCEPROP 1 LASTPIN (-3200 4500) $PN 1
J 0
(-3188 4512);
DISPLAY 0.787234 (-3188 4512);
PAINT MONO (-3188 4512);
FORCEPROP 1 LASTPIN (-3000 4500) $PN 2
J 0
(-3038 4512);
DISPLAY 0.787234 (-3038 4512);
PAINT MONO (-3038 4512);
FORCEPROP 1 LAST VALUE 0
J 2
(-3225 4500);
DISPLAY 0.510638 (-3225 4500);
FORCEPROP 1 LAST TOLERANCE 5%
J 0
(-3325 4500);
DISPLAY 0.510638 (-3325 4500);
FORCEPROP 1 LAST MATERIAL CHIP
J 0
(-3450 4500);
DISPLAY 0.510638 (-3450 4500);
FORCEPROP 1 LAST PACK_TYPE 0201LF
J 0
(-3600 4500);
DISPLAY 0.510638 (-3600 4500);
FORCEPROP 1 LAST WATTAGE 1/20W
J 2
(-3300 4575);
DISPLAY 0.510638 (-3300 4575);
DISPLAY INVISIBLE (-3300 4575);
FORCEPROP 2 LAST CDS_LIB pure_quanta
J 0
(-3100 4500);
DISPLAY INVISIBLE (-3100 4500);
FORCEPROP 1 LAST PATH I56
J 0
(-3150 4650);
DISPLAY 0.978723 (-3150 4650);
PAINT WHITE (-3150 4650);
DISPLAY INVISIBLE (-3150 4650);
FORCEPROP 1 LAST PART_NUMBER CS00001JE10
J 0
(-3150 4625);
DISPLAY 0.510638 (-3150 4625);
DISPLAY INVISIBLE (-3150 4625);
FORCEADD Q_RES..1
(-3100 4450);
FORCEPROP 1 LAST LOCATION R6757
J 0
(-2950 4450);
DISPLAY 0.638298 (-2950 4450);
FORCEPROP 0 LAST $SEC 1
J 0
(-2950 4500);
DISPLAY 0.680851 (-2950 4500);
PAINT MONO (-2950 4500);
DISPLAY INVISIBLE (-2950 4500);
FORCEPROP 0 LAST CDS_SEC 1
J 0
(-2950 4500);
DISPLAY 0.680851 (-2950 4500);
DISPLAY INVISIBLE (-2950 4500);
FORCEPROP 1 LASTPIN (-3200 4450) $PN 1
J 0
(-3188 4462);
DISPLAY 0.787234 (-3188 4462);
PAINT MONO (-3188 4462);
FORCEPROP 1 LASTPIN (-3000 4450) $PN 2
J 0
(-3038 4462);
DISPLAY 0.787234 (-3038 4462);
PAINT MONO (-3038 4462);
FORCEPROP 1 LAST VALUE 0
J 2
(-3225 4450);
DISPLAY 0.510638 (-3225 4450);
FORCEPROP 1 LAST TOLERANCE 5%
J 0
(-3325 4450);
DISPLAY 0.510638 (-3325 4450);
FORCEPROP 1 LAST MATERIAL CHIP
J 0
(-3450 4450);
DISPLAY 0.510638 (-3450 4450);
FORCEPROP 1 LAST PACK_TYPE 0201LF
J 0
(-3600 4450);
DISPLAY 0.510638 (-3600 4450);
FORCEPROP 1 LAST WATTAGE 1/20W
J 2
(-3300 4525);
DISPLAY 0.510638 (-3300 4525);
DISPLAY INVISIBLE (-3300 4525);
FORCEPROP 2 LAST CDS_LIB pure_quanta
J 0
(-3100 4450);
DISPLAY INVISIBLE (-3100 4450);
FORCEPROP 1 LAST PATH I57
J 0
(-3150 4600);
DISPLAY 0.978723 (-3150 4600);
PAINT WHITE (-3150 4600);
DISPLAY INVISIBLE (-3150 4600);
FORCEPROP 1 LAST PART_NUMBER CS00001JE10
J 0
(-3150 4575);
DISPLAY 0.510638 (-3150 4575);
DISPLAY INVISIBLE (-3150 4575);
FORCEADD Q_RES..1
(-3100 4300);
FORCEPROP 1 LAST LOCATION R6760
J 0
(-2950 4300);
DISPLAY 0.638298 (-2950 4300);
FORCEPROP 0 LAST $SEC 1
J 0
(-2950 4350);
DISPLAY 0.680851 (-2950 4350);
PAINT MONO (-2950 4350);
DISPLAY INVISIBLE (-2950 4350);
FORCEPROP 0 LAST CDS_SEC 1
J 0
(-2950 4350);
DISPLAY 0.680851 (-2950 4350);
DISPLAY INVISIBLE (-2950 4350);
FORCEPROP 1 LASTPIN (-3200 4300) $PN 1
J 0
(-3188 4312);
DISPLAY 0.787234 (-3188 4312);
PAINT MONO (-3188 4312);
FORCEPROP 1 LASTPIN (-3000 4300) $PN 2
J 0
(-3038 4312);
DISPLAY 0.787234 (-3038 4312);
PAINT MONO (-3038 4312);
FORCEPROP 1 LAST MATERIAL CHIP
J 0
(-3450 4300);
DISPLAY 0.510638 (-3450 4300);
FORCEPROP 1 LAST TOLERANCE 5%
J 0
(-3325 4300);
DISPLAY 0.510638 (-3325 4300);
FORCEPROP 1 LAST VALUE 0
J 2
(-3225 4300);
DISPLAY 0.510638 (-3225 4300);
FORCEPROP 1 LAST PACK_TYPE 0201LF
J 0
(-3600 4300);
DISPLAY 0.510638 (-3600 4300);
FORCEPROP 1 LAST WATTAGE 1/20W
J 2
(-3300 4375);
DISPLAY 0.510638 (-3300 4375);
DISPLAY INVISIBLE (-3300 4375);
FORCEPROP 2 LAST CDS_LIB pure_quanta
J 0
(-3100 4300);
DISPLAY INVISIBLE (-3100 4300);
FORCEPROP 1 LAST PATH I58
J 0
(-3150 4450);
DISPLAY 0.978723 (-3150 4450);
PAINT WHITE (-3150 4450);
DISPLAY INVISIBLE (-3150 4450);
FORCEPROP 1 LAST PART_NUMBER CS00001JE10
J 0
(-3150 4425);
DISPLAY 0.510638 (-3150 4425);
DISPLAY INVISIBLE (-3150 4425);
FORCEADD Q_RES..1
(-3100 4350);
FORCEPROP 1 LAST LOCATION R6759
J 0
(-2950 4350);
DISPLAY 0.638298 (-2950 4350);
FORCEPROP 0 LAST $SEC 1
J 0
(-2950 4400);
DISPLAY 0.680851 (-2950 4400);
PAINT MONO (-2950 4400);
DISPLAY INVISIBLE (-2950 4400);
FORCEPROP 0 LAST CDS_SEC 1
J 0
(-2950 4400);
DISPLAY 0.680851 (-2950 4400);
DISPLAY INVISIBLE (-2950 4400);
FORCEPROP 1 LASTPIN (-3200 4350) $PN 1
J 0
(-3188 4362);
DISPLAY 0.787234 (-3188 4362);
PAINT MONO (-3188 4362);
FORCEPROP 1 LASTPIN (-3000 4350) $PN 2
J 0
(-3038 4362);
DISPLAY 0.787234 (-3038 4362);
PAINT MONO (-3038 4362);
FORCEPROP 1 LAST TOLERANCE 5%
J 0
(-3325 4350);
DISPLAY 0.510638 (-3325 4350);
FORCEPROP 1 LAST MATERIAL CHIP
J 0
(-3450 4350);
DISPLAY 0.510638 (-3450 4350);
FORCEPROP 1 LAST PACK_TYPE 0201LF
J 0
(-3600 4350);
DISPLAY 0.510638 (-3600 4350);
FORCEPROP 1 LAST VALUE 0
J 2
(-3225 4350);
DISPLAY 0.510638 (-3225 4350);
FORCEPROP 1 LAST WATTAGE 1/20W
J 2
(-3300 4425);
DISPLAY 0.510638 (-3300 4425);
DISPLAY INVISIBLE (-3300 4425);
FORCEPROP 2 LAST CDS_LIB pure_quanta
J 0
(-3100 4350);
DISPLAY INVISIBLE (-3100 4350);
FORCEPROP 1 LAST PATH I59
J 0
(-3150 4500);
DISPLAY 0.978723 (-3150 4500);
PAINT WHITE (-3150 4500);
DISPLAY INVISIBLE (-3150 4500);
FORCEPROP 1 LAST PART_NUMBER CS00001JE10
J 0
(-3150 4475);
DISPLAY 0.510638 (-3150 4475);
DISPLAY INVISIBLE (-3150 4475);
FORCEADD Q_RES..1
(-6350 4600);
FORCEPROP 1 LAST LOCATION R6810
J 0
(-6200 4600);
DISPLAY 0.638298 (-6200 4600);
PAINT SKYBLUE (-6200 4600);
FORCEPROP 2 LAST SEC 1
J 0
(-6400 4800);
DISPLAY 0.680851 (-6400 4800);
PAINT MONO (-6400 4800);
DISPLAY INVISIBLE (-6400 4800);
FORCEPROP 1 LASTPIN (-6450 4600) $PN 1
J 0
(-6438 4612);
DISPLAY 0.787234 (-6438 4612);
PAINT MONO (-6438 4612);
FORCEPROP 1 LASTPIN (-6250 4600) $PN 2
J 0
(-6288 4612);
DISPLAY 0.787234 (-6288 4612);
PAINT MONO (-6288 4612);
FORCEPROP 1 LAST VALUE 0
J 2
(-6475 4600);
DISPLAY 0.510638 (-6475 4600);
FORCEPROP 1 LAST MATERIAL CHIP
J 0
(-6700 4600);
DISPLAY 0.510638 (-6700 4600);
FORCEPROP 1 LAST PACK_TYPE 0201LF
J 0
(-6850 4600);
DISPLAY 0.510638 (-6850 4600);
FORCEPROP 1 LAST TOLERANCE 5%
J 0
(-6575 4600);
DISPLAY 0.510638 (-6575 4600);
FORCEPROP 2 LAST CDS_LIB pure_quanta
J 0
(-6350 4600);
DISPLAY INVISIBLE (-6350 4600);
FORCEPROP 2 LAST SEC_TYPE 0201LF
J 0
(-6400 4800);
DISPLAY 0.680851 (-6400 4800);
DISPLAY INVISIBLE (-6400 4800);
FORCEPROP 1 LAST WATTAGE 1/20W
J 2
(-6550 4675);
DISPLAY 0.510638 (-6550 4675);
DISPLAY INVISIBLE (-6550 4675);
FORCEPROP 1 LAST PATH I6
J 0
(-6400 4750);
DISPLAY 0.978723 (-6400 4750);
PAINT WHITE (-6400 4750);
DISPLAY INVISIBLE (-6400 4750);
FORCEPROP 1 LAST PART_NUMBER CS00001JE10
J 0
(-6400 4725);
DISPLAY 0.510638 (-6400 4725);
DISPLAY INVISIBLE (-6400 4725);
FORCEADD Q_RES..1
(-3100 4250);
FORCEPROP 1 LAST LOCATION R6761
J 0
(-2950 4250);
DISPLAY 0.638298 (-2950 4250);
FORCEPROP 0 LAST $SEC 1
J 0
(-2950 4300);
DISPLAY 0.680851 (-2950 4300);
PAINT MONO (-2950 4300);
DISPLAY INVISIBLE (-2950 4300);
FORCEPROP 0 LAST CDS_SEC 1
J 0
(-2950 4300);
DISPLAY 0.680851 (-2950 4300);
DISPLAY INVISIBLE (-2950 4300);
FORCEPROP 1 LASTPIN (-3200 4250) $PN 1
J 0
(-3188 4262);
DISPLAY 0.787234 (-3188 4262);
PAINT MONO (-3188 4262);
FORCEPROP 1 LASTPIN (-3000 4250) $PN 2
J 0
(-3038 4262);
DISPLAY 0.787234 (-3038 4262);
PAINT MONO (-3038 4262);
FORCEPROP 1 LAST TOLERANCE 5%
J 0
(-3325 4250);
DISPLAY 0.510638 (-3325 4250);
FORCEPROP 1 LAST VALUE 0
J 2
(-3225 4250);
DISPLAY 0.510638 (-3225 4250);
FORCEPROP 1 LAST PACK_TYPE 0201LF
J 0
(-3600 4250);
DISPLAY 0.510638 (-3600 4250);
FORCEPROP 1 LAST MATERIAL CHIP
J 0
(-3450 4250);
DISPLAY 0.510638 (-3450 4250);
FORCEPROP 2 LAST CDS_LIB pure_quanta
J 0
(-3100 4250);
DISPLAY INVISIBLE (-3100 4250);
FORCEPROP 1 LAST WATTAGE 1/20W
J 2
(-3300 4325);
DISPLAY 0.510638 (-3300 4325);
DISPLAY INVISIBLE (-3300 4325);
FORCEPROP 1 LAST PATH I60
J 0
(-3150 4400);
DISPLAY 0.978723 (-3150 4400);
PAINT WHITE (-3150 4400);
DISPLAY INVISIBLE (-3150 4400);
FORCEPROP 1 LAST PART_NUMBER CS00001JE10
J 0
(-3150 4375);
DISPLAY 0.510638 (-3150 4375);
DISPLAY INVISIBLE (-3150 4375);
FORCEADD OFFPAGE..2
(-1675 4550);
FORCEPROP 2 LAST $XR1 277 
J 0
(-1366 4550);
DISPLAY 0.638298 (-1366 4550);
PAINT MONO (-1366 4550);
FORCEPROP 2 LAST $XR0 184 
J 0
(-1486 4550);
DISPLAY 0.638298 (-1486 4550);
PAINT MONO (-1486 4550);
FORCEPROP 2 LAST CDS_LIB standard
J 0
(-1675 4550);
DISPLAY INVISIBLE (-1675 4550);
FORCEPROP 1 LAST OFFPAGE TRUE
J 0
(-1350 4425);
DISPLAY 0.872340 (-1350 4425);
PAINT GREEN (-1350 4425);
DISPLAY INVISIBLE (-1350 4425);
FORCEPROP 1 LAST COMMENT_BODY TRUE
J 0
(-1720 4455);
DISPLAY 0.872340 (-1720 4455);
PAINT GREEN (-1720 4455);
DISPLAY INVISIBLE (-1720 4455);
FORCEPROP 2 LAST PATH I61
J 2
(-1725 4625);
DISPLAY 0.680851 (-1725 4625);
DISPLAY INVISIBLE (-1725 4625);
FORCEADD OFFPAGE..3
(-1700 4600);
FORCEPROP 2 LAST $XR1 277 
J 0
(-1366 4600);
DISPLAY 0.638298 (-1366 4600);
PAINT MONO (-1366 4600);
FORCEPROP 2 LAST $XR0 184 
J 0
(-1486 4600);
DISPLAY 0.638298 (-1486 4600);
PAINT MONO (-1486 4600);
FORCEPROP 2 LAST CDS_LIB standard
J 0
(-1700 4600);
DISPLAY INVISIBLE (-1700 4600);
FORCEPROP 1 LAST OFFPAGE TRUE
J 0
(-1375 4475);
DISPLAY 0.872340 (-1375 4475);
PAINT GREEN (-1375 4475);
DISPLAY INVISIBLE (-1375 4475);
FORCEPROP 1 LAST COMMENT_BODY TRUE
J 0
(-1750 4500);
DISPLAY 0.872340 (-1750 4500);
PAINT GREEN (-1750 4500);
DISPLAY INVISIBLE (-1750 4500);
FORCEPROP 2 LAST PATH I62
J 2
(-1750 4675);
DISPLAY 0.680851 (-1750 4675);
DISPLAY INVISIBLE (-1750 4675);
FORCEADD OFFPAGE..2
(-1700 4450);
FORCEPROP 2 LAST $XR1 288 
J 0
(-1361 4450);
DISPLAY 0.638298 (-1361 4450);
PAINT MONO (-1361 4450);
FORCEPROP 2 LAST $XR0 184 
J 0
(-1481 4450);
DISPLAY 0.638298 (-1481 4450);
PAINT MONO (-1481 4450);
FORCEPROP 2 LAST CDS_LIB standard
J 0
(-1700 4450);
DISPLAY INVISIBLE (-1700 4450);
FORCEPROP 1 LAST OFFPAGE TRUE
J 0
(-1375 4325);
DISPLAY 0.872340 (-1375 4325);
PAINT GREEN (-1375 4325);
DISPLAY INVISIBLE (-1375 4325);
FORCEPROP 1 LAST COMMENT_BODY TRUE
J 0
(-1745 4355);
DISPLAY 0.872340 (-1745 4355);
PAINT GREEN (-1745 4355);
DISPLAY INVISIBLE (-1745 4355);
FORCEPROP 2 LAST PATH I63
J 0
(-1525 4525);
DISPLAY 0.680851 (-1525 4525);
DISPLAY INVISIBLE (-1525 4525);
FORCEADD OFFPAGE..3
(-1700 4500);
FORCEPROP 2 LAST $XR1 288 
J 0
(-1366 4500);
DISPLAY 0.638298 (-1366 4500);
PAINT MONO (-1366 4500);
FORCEPROP 2 LAST $XR0 184 
J 0
(-1486 4500);
DISPLAY 0.638298 (-1486 4500);
PAINT MONO (-1486 4500);
FORCEPROP 2 LAST CDS_LIB standard
J 0
(-1700 4500);
DISPLAY INVISIBLE (-1700 4500);
FORCEPROP 1 LAST OFFPAGE TRUE
J 0
(-1375 4375);
DISPLAY 0.872340 (-1375 4375);
PAINT GREEN (-1375 4375);
DISPLAY INVISIBLE (-1375 4375);
FORCEPROP 1 LAST COMMENT_BODY TRUE
J 0
(-1750 4400);
DISPLAY 0.872340 (-1750 4400);
PAINT GREEN (-1750 4400);
DISPLAY INVISIBLE (-1750 4400);
FORCEPROP 2 LAST PATH I64
J 0
(-1500 4575);
DISPLAY 0.680851 (-1500 4575);
DISPLAY INVISIBLE (-1500 4575);
FORCEADD OFFPAGE..2
(-1700 4350);
FORCEPROP 2 LAST $XR1 310 
J 0
(-1361 4350);
DISPLAY 0.638298 (-1361 4350);
PAINT MONO (-1361 4350);
FORCEPROP 2 LAST $XR0 184 
J 0
(-1481 4350);
DISPLAY 0.638298 (-1481 4350);
PAINT MONO (-1481 4350);
FORCEPROP 2 LAST CDS_LIB standard
J 0
(-1700 4350);
DISPLAY INVISIBLE (-1700 4350);
FORCEPROP 1 LAST OFFPAGE TRUE
J 0
(-1375 4225);
DISPLAY 0.872340 (-1375 4225);
PAINT GREEN (-1375 4225);
DISPLAY INVISIBLE (-1375 4225);
FORCEPROP 1 LAST COMMENT_BODY TRUE
J 0
(-1745 4255);
DISPLAY 0.872340 (-1745 4255);
PAINT GREEN (-1745 4255);
DISPLAY INVISIBLE (-1745 4255);
FORCEPROP 2 LAST PATH I65
J 0
(-1525 4425);
DISPLAY 0.680851 (-1525 4425);
DISPLAY INVISIBLE (-1525 4425);
FORCEADD OFFPAGE..3
(-1700 4400);
FORCEPROP 2 LAST $XR1 310 
J 0
(-1366 4400);
DISPLAY 0.638298 (-1366 4400);
PAINT MONO (-1366 4400);
FORCEPROP 2 LAST $XR0 184 
J 0
(-1486 4400);
DISPLAY 0.638298 (-1486 4400);
PAINT MONO (-1486 4400);
FORCEPROP 2 LAST CDS_LIB standard
J 0
(-1700 4400);
DISPLAY INVISIBLE (-1700 4400);
FORCEPROP 1 LAST OFFPAGE TRUE
J 0
(-1375 4275);
DISPLAY 0.872340 (-1375 4275);
PAINT GREEN (-1375 4275);
DISPLAY INVISIBLE (-1375 4275);
FORCEPROP 1 LAST COMMENT_BODY TRUE
J 0
(-1750 4300);
DISPLAY 0.872340 (-1750 4300);
PAINT GREEN (-1750 4300);
DISPLAY INVISIBLE (-1750 4300);
FORCEPROP 2 LAST PATH I66
J 0
(-1500 4475);
DISPLAY 0.680851 (-1500 4475);
DISPLAY INVISIBLE (-1500 4475);
FORCEADD OFFPAGE..2
(-1700 4250);
FORCEPROP 2 LAST $XR1 299 
J 0
(-1361 4250);
DISPLAY 0.638298 (-1361 4250);
PAINT MONO (-1361 4250);
FORCEPROP 2 LAST $XR0 184 
J 0
(-1481 4250);
DISPLAY 0.638298 (-1481 4250);
PAINT MONO (-1481 4250);
FORCEPROP 2 LAST CDS_LIB standard
J 0
(-1700 4250);
DISPLAY INVISIBLE (-1700 4250);
FORCEPROP 1 LAST OFFPAGE TRUE
J 0
(-1375 4125);
DISPLAY 0.872340 (-1375 4125);
PAINT GREEN (-1375 4125);
DISPLAY INVISIBLE (-1375 4125);
FORCEPROP 1 LAST COMMENT_BODY TRUE
J 0
(-1745 4155);
DISPLAY 0.872340 (-1745 4155);
PAINT GREEN (-1745 4155);
DISPLAY INVISIBLE (-1745 4155);
FORCEPROP 2 LAST PATH I67
J 0
(-1525 4325);
DISPLAY 0.680851 (-1525 4325);
DISPLAY INVISIBLE (-1525 4325);
FORCEADD OFFPAGE..3
(-1700 4300);
FORCEPROP 2 LAST $XR1 299 
J 0
(-1366 4300);
DISPLAY 0.638298 (-1366 4300);
PAINT MONO (-1366 4300);
FORCEPROP 2 LAST $XR0 184 
J 0
(-1486 4300);
DISPLAY 0.638298 (-1486 4300);
PAINT MONO (-1486 4300);
FORCEPROP 2 LAST CDS_LIB standard
J 0
(-1700 4300);
DISPLAY INVISIBLE (-1700 4300);
FORCEPROP 1 LAST OFFPAGE TRUE
J 0
(-1375 4175);
DISPLAY 0.872340 (-1375 4175);
PAINT GREEN (-1375 4175);
DISPLAY INVISIBLE (-1375 4175);
FORCEPROP 1 LAST COMMENT_BODY TRUE
J 0
(-1750 4200);
DISPLAY 0.872340 (-1750 4200);
PAINT GREEN (-1750 4200);
DISPLAY INVISIBLE (-1750 4200);
FORCEPROP 2 LAST PATH I68
J 0
(-1500 4375);
DISPLAY 0.680851 (-1500 4375);
DISPLAY INVISIBLE (-1500 4375);
FORCEADD OFFPAGE..2
(-4100 1525);
FORCEPROP 2 LAST $XR1 277 
J 0
(-3791 1525);
DISPLAY 0.638298 (-3791 1525);
PAINT MONO (-3791 1525);
FORCEPROP 2 LAST $XR0 184 
J 0
(-3911 1525);
DISPLAY 0.638298 (-3911 1525);
PAINT MONO (-3911 1525);
FORCEPROP 2 LAST CDS_LIB standard
J 2
(-4100 1525);
DISPLAY INVISIBLE (-4100 1525);
FORCEPROP 1 LAST OFFPAGE TRUE
J 0
(-3775 1400);
DISPLAY 0.872340 (-3775 1400);
PAINT GREEN (-3775 1400);
DISPLAY INVISIBLE (-3775 1400);
FORCEPROP 1 LAST COMMENT_BODY TRUE
J 0
(-4145 1430);
DISPLAY 0.872340 (-4145 1430);
PAINT GREEN (-4145 1430);
DISPLAY INVISIBLE (-4145 1430);
FORCEPROP 2 LAST PATH I69
J 0
(-3775 1575);
DISPLAY 0.680851 (-3775 1575);
DISPLAY INVISIBLE (-3775 1575);
FORCEADD Q_RES..1
(-6350 4550);
FORCEPROP 1 LAST LOCATION R6811
J 0
(-6200 4550);
DISPLAY 0.638298 (-6200 4550);
PAINT SKYBLUE (-6200 4550);
FORCEPROP 2 LAST SEC 1
J 0
(-6400 4750);
DISPLAY 0.680851 (-6400 4750);
PAINT MONO (-6400 4750);
DISPLAY INVISIBLE (-6400 4750);
FORCEPROP 1 LASTPIN (-6450 4550) $PN 1
J 0
(-6438 4562);
DISPLAY 0.787234 (-6438 4562);
PAINT MONO (-6438 4562);
FORCEPROP 1 LASTPIN (-6250 4550) $PN 2
J 0
(-6288 4562);
DISPLAY 0.787234 (-6288 4562);
PAINT MONO (-6288 4562);
FORCEPROP 1 LAST MATERIAL CHIP
J 0
(-6700 4550);
DISPLAY 0.510638 (-6700 4550);
FORCEPROP 1 LAST PACK_TYPE 0201LF
J 0
(-6850 4550);
DISPLAY 0.510638 (-6850 4550);
FORCEPROP 1 LAST VALUE 0
J 2
(-6475 4550);
DISPLAY 0.510638 (-6475 4550);
FORCEPROP 1 LAST TOLERANCE 5%
J 0
(-6575 4550);
DISPLAY 0.510638 (-6575 4550);
FORCEPROP 2 LAST CDS_LIB pure_quanta
J 0
(-6350 4550);
DISPLAY INVISIBLE (-6350 4550);
FORCEPROP 2 LAST SEC_TYPE 0201LF
J 0
(-6400 4750);
DISPLAY 0.680851 (-6400 4750);
DISPLAY INVISIBLE (-6400 4750);
FORCEPROP 1 LAST WATTAGE 1/20W
J 2
(-6550 4625);
DISPLAY 0.510638 (-6550 4625);
DISPLAY INVISIBLE (-6550 4625);
FORCEPROP 1 LAST PATH I7
J 0
(-6400 4700);
DISPLAY 0.978723 (-6400 4700);
PAINT WHITE (-6400 4700);
DISPLAY INVISIBLE (-6400 4700);
FORCEPROP 1 LAST PART_NUMBER CS00001JE10
J 0
(-6400 4675);
DISPLAY 0.510638 (-6400 4675);
DISPLAY INVISIBLE (-6400 4675);
FORCEADD OFFPAGE..2
(-4100 1425);
FORCEPROP 2 LAST $XR1 277 
J 0
(-3791 1425);
DISPLAY 0.638298 (-3791 1425);
PAINT MONO (-3791 1425);
FORCEPROP 2 LAST $XR0 184 
J 0
(-3911 1425);
DISPLAY 0.638298 (-3911 1425);
PAINT MONO (-3911 1425);
FORCEPROP 2 LAST CDS_LIB standard
J 0
(-4100 1425);
DISPLAY INVISIBLE (-4100 1425);
FORCEPROP 1 LAST OFFPAGE TRUE
J 0
(-3775 1300);
DISPLAY 0.872340 (-3775 1300);
PAINT GREEN (-3775 1300);
DISPLAY INVISIBLE (-3775 1300);
FORCEPROP 1 LAST COMMENT_BODY TRUE
J 0
(-4145 1330);
DISPLAY 0.872340 (-4145 1330);
PAINT GREEN (-4145 1330);
DISPLAY INVISIBLE (-4145 1330);
FORCEPROP 2 LAST PATH I70
J 0
(-3775 1475);
DISPLAY 0.680851 (-3775 1475);
DISPLAY INVISIBLE (-3775 1475);
FORCEADD OFFPAGE..2
(-4100 1350);
FORCEPROP 2 LAST $XR1 288 
J 0
(-3791 1350);
DISPLAY 0.638298 (-3791 1350);
PAINT MONO (-3791 1350);
FORCEPROP 2 LAST $XR0 184 
J 0
(-3911 1350);
DISPLAY 0.638298 (-3911 1350);
PAINT MONO (-3911 1350);
FORCEPROP 2 LAST CDS_LIB standard
J 0
(-4100 1350);
DISPLAY INVISIBLE (-4100 1350);
FORCEPROP 1 LAST OFFPAGE TRUE
J 0
(-3775 1225);
DISPLAY 0.872340 (-3775 1225);
PAINT GREEN (-3775 1225);
DISPLAY INVISIBLE (-3775 1225);
FORCEPROP 1 LAST COMMENT_BODY TRUE
J 0
(-4145 1255);
DISPLAY 0.872340 (-4145 1255);
PAINT GREEN (-4145 1255);
DISPLAY INVISIBLE (-4145 1255);
FORCEPROP 2 LAST PATH I71
J 0
(-3775 1400);
DISPLAY 0.680851 (-3775 1400);
DISPLAY INVISIBLE (-3775 1400);
FORCEADD OFFPAGE..2
(-4100 1275);
FORCEPROP 2 LAST $XR1 288 
J 0
(-3791 1275);
DISPLAY 0.638298 (-3791 1275);
PAINT MONO (-3791 1275);
FORCEPROP 2 LAST $XR0 184 
J 0
(-3911 1275);
DISPLAY 0.638298 (-3911 1275);
PAINT MONO (-3911 1275);
FORCEPROP 2 LAST CDS_LIB standard
J 0
(-4100 1275);
DISPLAY INVISIBLE (-4100 1275);
FORCEPROP 1 LAST OFFPAGE TRUE
J 0
(-3775 1150);
DISPLAY 0.872340 (-3775 1150);
PAINT GREEN (-3775 1150);
DISPLAY INVISIBLE (-3775 1150);
FORCEPROP 1 LAST COMMENT_BODY TRUE
J 0
(-4145 1180);
DISPLAY 0.872340 (-4145 1180);
PAINT GREEN (-4145 1180);
DISPLAY INVISIBLE (-4145 1180);
FORCEPROP 2 LAST PATH I72
J 0
(-3775 1325);
DISPLAY 0.680851 (-3775 1325);
DISPLAY INVISIBLE (-3775 1325);
FORCEADD OFFPAGE..2
(-4100 1175);
FORCEPROP 2 LAST $XR1 310 
J 0
(-3791 1175);
DISPLAY 0.638298 (-3791 1175);
PAINT MONO (-3791 1175);
FORCEPROP 2 LAST $XR0 184 
J 0
(-3911 1175);
DISPLAY 0.638298 (-3911 1175);
PAINT MONO (-3911 1175);
FORCEPROP 2 LAST CDS_LIB standard
J 0
(-4100 1175);
DISPLAY INVISIBLE (-4100 1175);
FORCEPROP 1 LAST OFFPAGE TRUE
J 0
(-3775 1050);
DISPLAY 0.872340 (-3775 1050);
PAINT GREEN (-3775 1050);
DISPLAY INVISIBLE (-3775 1050);
FORCEPROP 1 LAST COMMENT_BODY TRUE
J 0
(-4145 1080);
DISPLAY 0.872340 (-4145 1080);
PAINT GREEN (-4145 1080);
DISPLAY INVISIBLE (-4145 1080);
FORCEPROP 2 LAST PATH I73
J 0
(-3925 1250);
DISPLAY 0.680851 (-3925 1250);
DISPLAY INVISIBLE (-3925 1250);
FORCEADD OFFPAGE..2
(-4100 1100);
FORCEPROP 2 LAST $XR1 310 
J 0
(-3791 1100);
DISPLAY 0.638298 (-3791 1100);
PAINT MONO (-3791 1100);
FORCEPROP 2 LAST $XR0 184 
J 0
(-3911 1100);
DISPLAY 0.638298 (-3911 1100);
PAINT MONO (-3911 1100);
FORCEPROP 2 LAST CDS_LIB standard
J 0
(-4100 1100);
DISPLAY INVISIBLE (-4100 1100);
FORCEPROP 1 LAST OFFPAGE TRUE
J 0
(-3775 975);
DISPLAY 0.872340 (-3775 975);
PAINT GREEN (-3775 975);
DISPLAY INVISIBLE (-3775 975);
FORCEPROP 1 LAST COMMENT_BODY TRUE
J 0
(-4145 1005);
DISPLAY 0.872340 (-4145 1005);
PAINT GREEN (-4145 1005);
DISPLAY INVISIBLE (-4145 1005);
FORCEPROP 2 LAST PATH I74
J 0
(-3925 1175);
DISPLAY 0.680851 (-3925 1175);
DISPLAY INVISIBLE (-3925 1175);
FORCEADD OFFPAGE..2
(-4100 1025);
FORCEPROP 2 LAST $XR1 299 
J 0
(-3791 1025);
DISPLAY 0.638298 (-3791 1025);
PAINT MONO (-3791 1025);
FORCEPROP 2 LAST $XR0 184 
J 0
(-3911 1025);
DISPLAY 0.638298 (-3911 1025);
PAINT MONO (-3911 1025);
FORCEPROP 2 LAST CDS_LIB standard
J 0
(-4100 1025);
DISPLAY INVISIBLE (-4100 1025);
FORCEPROP 1 LAST OFFPAGE TRUE
J 0
(-3775 900);
DISPLAY 0.872340 (-3775 900);
PAINT GREEN (-3775 900);
DISPLAY INVISIBLE (-3775 900);
FORCEPROP 1 LAST COMMENT_BODY TRUE
J 0
(-4145 930);
DISPLAY 0.872340 (-4145 930);
PAINT GREEN (-4145 930);
DISPLAY INVISIBLE (-4145 930);
FORCEPROP 2 LAST PATH I75
J 0
(-3925 1100);
DISPLAY 0.680851 (-3925 1100);
DISPLAY INVISIBLE (-3925 1100);
FORCEADD OFFPAGE..2
(-4100 950);
FORCEPROP 2 LAST $XR1 299 
J 0
(-3791 950);
DISPLAY 0.638298 (-3791 950);
PAINT MONO (-3791 950);
FORCEPROP 2 LAST $XR0 184 
J 0
(-3911 950);
DISPLAY 0.638298 (-3911 950);
PAINT MONO (-3911 950);
FORCEPROP 2 LAST CDS_LIB standard
J 0
(-4100 950);
DISPLAY INVISIBLE (-4100 950);
FORCEPROP 1 LAST OFFPAGE TRUE
J 0
(-3775 825);
DISPLAY 0.872340 (-3775 825);
PAINT GREEN (-3775 825);
DISPLAY INVISIBLE (-3775 825);
FORCEPROP 1 LAST COMMENT_BODY TRUE
J 0
(-4145 855);
DISPLAY 0.872340 (-4145 855);
PAINT GREEN (-4145 855);
DISPLAY INVISIBLE (-4145 855);
FORCEPROP 2 LAST PATH I76
J 0
(-3925 1025);
DISPLAY 0.680851 (-3925 1025);
DISPLAY INVISIBLE (-3925 1025);
FORCEADD Q_RES..1
(-5950 1525);
FORCEPROP 1 LAST LOCATION R6762
J 0
(-6250 1525);
DISPLAY 0.978723 (-6250 1525);
PAINT SKYBLUE (-6250 1525);
FORCEPROP 0 LAST $SEC 1
J 0
(-5575 1775);
DISPLAY 0.680851 (-5575 1775);
PAINT MONO (-5575 1775);
DISPLAY INVISIBLE (-5575 1775);
FORCEPROP 0 LAST CDS_SEC 1
J 0
(-5575 1775);
DISPLAY 0.680851 (-5575 1775);
DISPLAY INVISIBLE (-5575 1775);
FORCEPROP 1 LASTPIN (-6050 1525) $PN 1
J 0
(-6038 1537);
DISPLAY 0.787234 (-6038 1537);
PAINT MONO (-6038 1537);
FORCEPROP 1 LASTPIN (-5850 1525) $PN 2
J 0
(-5888 1537);
DISPLAY 0.787234 (-5888 1537);
PAINT MONO (-5888 1537);
FORCEPROP 1 LAST WATTAGE 1/20W
J 2
(-5575 1725);
DISPLAY 0.978723 (-5575 1725);
FORCEPROP 1 LAST TOLERANCE 1%
J 0
(-5975 1725);
DISPLAY 0.978723 (-5975 1725);
FORCEPROP 1 LAST VALUE 1K
J 2
(-5675 1525);
DISPLAY 0.978723 (-5675 1525);
FORCEPROP 1 LAST MATERIAL CHIP
J 0
(-5650 1525);
DISPLAY 0.978723 (-5650 1525);
FORCEPROP 1 LAST PACK_TYPE 0201LF
J 0
(-5425 1525);
DISPLAY 0.978723 (-5425 1525);
FORCEPROP 2 LAST CDS_LIB pure_quanta
J 0
(-5950 1525);
DISPLAY INVISIBLE (-5950 1525);
FORCEPROP 1 LAST PATH I77
J 0
(-6000 1675);
DISPLAY 0.978723 (-6000 1675);
PAINT WHITE (-6000 1675);
DISPLAY INVISIBLE (-6000 1675);
FORCEPROP 1 LAST PART_NUMBER CS21001FE07
J 0
(-6000 1625);
DISPLAY 0.978723 (-6000 1625);
DISPLAY INVISIBLE (-6000 1625);
FORCEADD Q_RES..1
(-5950 1425);
FORCEPROP 1 LAST LOCATION R6763
J 0
(-6250 1425);
DISPLAY 0.978723 (-6250 1425);
PAINT SKYBLUE (-6250 1425);
FORCEPROP 0 LAST $SEC 1
J 0
(-5425 1475);
DISPLAY 0.680851 (-5425 1475);
PAINT MONO (-5425 1475);
DISPLAY INVISIBLE (-5425 1475);
FORCEPROP 0 LAST CDS_SEC 1
J 0
(-5425 1475);
DISPLAY 0.680851 (-5425 1475);
DISPLAY INVISIBLE (-5425 1475);
FORCEPROP 1 LASTPIN (-6050 1425) $PN 1
J 0
(-6038 1437);
DISPLAY 0.787234 (-6038 1437);
PAINT MONO (-6038 1437);
FORCEPROP 1 LASTPIN (-5850 1425) $PN 2
J 0
(-5888 1437);
DISPLAY 0.787234 (-5888 1437);
PAINT MONO (-5888 1437);
FORCEPROP 1 LAST VALUE 1K
J 2
(-5675 1425);
DISPLAY 0.978723 (-5675 1425);
FORCEPROP 1 LAST MATERIAL CHIP
J 0
(-5650 1425);
DISPLAY 0.978723 (-5650 1425);
FORCEPROP 1 LAST PACK_TYPE 0201LF
J 0
(-5425 1425);
DISPLAY 0.978723 (-5425 1425);
FORCEPROP 2 LAST CDS_LIB pure_quanta
J 0
(-5950 1425);
DISPLAY INVISIBLE (-5950 1425);
FORCEPROP 1 LAST WATTAGE 1/20W
J 2
(-5575 1625);
DISPLAY 0.978723 (-5575 1625);
DISPLAY INVISIBLE (-5575 1625);
FORCEPROP 1 LAST TOLERANCE 1%
J 0
(-5975 1625);
DISPLAY 0.978723 (-5975 1625);
DISPLAY INVISIBLE (-5975 1625);
FORCEPROP 1 LAST PATH I78
J 0
(-6000 1575);
DISPLAY 0.978723 (-6000 1575);
PAINT WHITE (-6000 1575);
DISPLAY INVISIBLE (-6000 1575);
FORCEPROP 1 LAST PART_NUMBER CS21001FE07
J 0
(-6000 1525);
DISPLAY 0.978723 (-6000 1525);
DISPLAY INVISIBLE (-6000 1525);
FORCEADD Q_RES..1
(-5950 1350);
FORCEPROP 1 LAST LOCATION R6764
J 0
(-6250 1350);
DISPLAY 0.978723 (-6250 1350);
PAINT SKYBLUE (-6250 1350);
FORCEPROP 0 LAST $SEC 1
J 0
(-5425 1400);
DISPLAY 0.680851 (-5425 1400);
PAINT MONO (-5425 1400);
DISPLAY INVISIBLE (-5425 1400);
FORCEPROP 0 LAST CDS_SEC 1
J 0
(-5425 1400);
DISPLAY 0.680851 (-5425 1400);
DISPLAY INVISIBLE (-5425 1400);
FORCEPROP 1 LASTPIN (-6050 1350) $PN 1
J 0
(-6038 1362);
DISPLAY 0.787234 (-6038 1362);
PAINT MONO (-6038 1362);
FORCEPROP 1 LASTPIN (-5850 1350) $PN 2
J 0
(-5888 1362);
DISPLAY 0.787234 (-5888 1362);
PAINT MONO (-5888 1362);
FORCEPROP 1 LAST MATERIAL CHIP
J 0
(-5650 1350);
DISPLAY 0.978723 (-5650 1350);
FORCEPROP 1 LAST PACK_TYPE 0201LF
J 0
(-5425 1350);
DISPLAY 0.978723 (-5425 1350);
FORCEPROP 1 LAST VALUE 1K
J 2
(-5675 1350);
DISPLAY 0.978723 (-5675 1350);
FORCEPROP 1 LAST TOLERANCE 1%
J 0
(-5975 1550);
DISPLAY 0.978723 (-5975 1550);
DISPLAY INVISIBLE (-5975 1550);
FORCEPROP 1 LAST WATTAGE 1/20W
J 2
(-5575 1550);
DISPLAY 0.978723 (-5575 1550);
DISPLAY INVISIBLE (-5575 1550);
FORCEPROP 2 LAST CDS_LIB pure_quanta
J 0
(-5950 1350);
DISPLAY INVISIBLE (-5950 1350);
FORCEPROP 1 LAST PATH I79
J 0
(-6000 1500);
DISPLAY 0.978723 (-6000 1500);
PAINT WHITE (-6000 1500);
DISPLAY INVISIBLE (-6000 1500);
FORCEPROP 1 LAST PART_NUMBER CS21001FE07
J 0
(-6000 1450);
DISPLAY 0.978723 (-6000 1450);
DISPLAY INVISIBLE (-6000 1450);
FORCEADD P1V0..1
(-3150 1750);
FORCEPROP 3 LASTPIN (-3150 1700) SIG_NAME P1V8_CPU1_RT_1D\g
J 0
(-3140 1710);
DISPLAY 0.659574 (-3140 1710);
PAINT MONO (-3140 1710);
DISPLAY INVISIBLE (-3140 1710);
FORCEPROP 1 LAST HDL_POWER P1V8_CPU1_RT_1D
J 1
(-3150 1800);
DISPLAY 0.957447 (-3150 1800);
PAINT SKYBLUE (-3150 1800);
FORCEPROP 2 LAST CDS_LIB pure_quanta_power
J 0
(-3150 1750);
DISPLAY INVISIBLE (-3150 1750);
FORCEPROP 1 LAST PATH I8
J 0
(-3100 1775);
DISPLAY 0.872340 (-3100 1775);
PAINT AQUA (-3100 1775);
DISPLAY INVISIBLE (-3100 1775);
FORCEADD Q_RES..1
(-5950 1275);
FORCEPROP 1 LAST LOCATION R6765
J 0
(-6250 1275);
DISPLAY 0.978723 (-6250 1275);
PAINT SKYBLUE (-6250 1275);
FORCEPROP 0 LAST $SEC 1
J 0
(-5425 1325);
DISPLAY 0.680851 (-5425 1325);
PAINT MONO (-5425 1325);
DISPLAY INVISIBLE (-5425 1325);
FORCEPROP 0 LAST CDS_SEC 1
J 0
(-5425 1325);
DISPLAY 0.680851 (-5425 1325);
DISPLAY INVISIBLE (-5425 1325);
FORCEPROP 1 LASTPIN (-6050 1275) $PN 1
J 0
(-6038 1287);
DISPLAY 0.787234 (-6038 1287);
PAINT MONO (-6038 1287);
FORCEPROP 1 LASTPIN (-5850 1275) $PN 2
J 0
(-5888 1287);
DISPLAY 0.787234 (-5888 1287);
PAINT MONO (-5888 1287);
FORCEPROP 1 LAST MATERIAL CHIP
J 0
(-5650 1275);
DISPLAY 0.978723 (-5650 1275);
FORCEPROP 1 LAST PACK_TYPE 0201LF
J 0
(-5425 1275);
DISPLAY 0.978723 (-5425 1275);
FORCEPROP 1 LAST VALUE 1K
J 2
(-5675 1275);
DISPLAY 0.978723 (-5675 1275);
FORCEPROP 1 LAST WATTAGE 1/20W
J 2
(-5575 1475);
DISPLAY 0.978723 (-5575 1475);
DISPLAY INVISIBLE (-5575 1475);
FORCEPROP 1 LAST TOLERANCE 1%
J 0
(-5975 1475);
DISPLAY 0.978723 (-5975 1475);
DISPLAY INVISIBLE (-5975 1475);
FORCEPROP 2 LAST CDS_LIB pure_quanta
J 0
(-5950 1275);
DISPLAY INVISIBLE (-5950 1275);
FORCEPROP 1 LAST PATH I80
J 0
(-6000 1425);
DISPLAY 0.978723 (-6000 1425);
PAINT WHITE (-6000 1425);
DISPLAY INVISIBLE (-6000 1425);
FORCEPROP 1 LAST PART_NUMBER CS21001FE07
J 0
(-6000 1375);
DISPLAY 0.978723 (-6000 1375);
DISPLAY INVISIBLE (-6000 1375);
FORCEADD P1V0..1
(-6475 1825);
FORCEPROP 3 LASTPIN (-6475 1775) SIG_NAME P1V8_CPU0_RT_1D\g
J 0
(-6465 1785);
DISPLAY 0.659574 (-6465 1785);
PAINT MONO (-6465 1785);
DISPLAY INVISIBLE (-6465 1785);
FORCEPROP 1 LAST HDL_POWER P1V8_CPU0_RT_1D
J 1
(-6475 1875);
DISPLAY 0.957447 (-6475 1875);
PAINT SKYBLUE (-6475 1875);
FORCEPROP 2 LAST CDS_LIB pure_quanta_power
J 0
(-6475 1825);
DISPLAY INVISIBLE (-6475 1825);
FORCEPROP 1 LAST PATH I81
J 0
(-6425 1850);
DISPLAY 0.872340 (-6425 1850);
PAINT AQUA (-6425 1850);
DISPLAY INVISIBLE (-6425 1850);
FORCEADD Q_RES..1
(-5950 1100);
FORCEPROP 1 LAST LOCATION R6767
J 0
(-6250 1100);
DISPLAY 0.978723 (-6250 1100);
PAINT SKYBLUE (-6250 1100);
FORCEPROP 0 LAST $SEC 1
J 0
(-5425 1150);
DISPLAY 0.680851 (-5425 1150);
PAINT MONO (-5425 1150);
DISPLAY INVISIBLE (-5425 1150);
FORCEPROP 0 LAST CDS_SEC 1
J 0
(-5425 1150);
DISPLAY 0.680851 (-5425 1150);
DISPLAY INVISIBLE (-5425 1150);
FORCEPROP 1 LASTPIN (-6050 1100) $PN 1
J 0
(-6038 1112);
DISPLAY 0.787234 (-6038 1112);
PAINT MONO (-6038 1112);
FORCEPROP 1 LASTPIN (-5850 1100) $PN 2
J 0
(-5888 1112);
DISPLAY 0.787234 (-5888 1112);
PAINT MONO (-5888 1112);
FORCEPROP 1 LAST VALUE 1K
J 2
(-5675 1100);
DISPLAY 0.978723 (-5675 1100);
FORCEPROP 1 LAST MATERIAL CHIP
J 0
(-5650 1100);
DISPLAY 0.978723 (-5650 1100);
FORCEPROP 1 LAST PACK_TYPE 0201LF
J 0
(-5425 1100);
DISPLAY 0.978723 (-5425 1100);
FORCEPROP 2 LAST CDS_LIB pure_quanta
J 0
(-5950 1100);
DISPLAY INVISIBLE (-5950 1100);
FORCEPROP 1 LAST WATTAGE 1/20W
J 2
(-5575 1300);
DISPLAY 0.978723 (-5575 1300);
DISPLAY INVISIBLE (-5575 1300);
FORCEPROP 1 LAST TOLERANCE 1%
J 0
(-5975 1300);
DISPLAY 0.978723 (-5975 1300);
DISPLAY INVISIBLE (-5975 1300);
FORCEPROP 1 LAST PATH I82
J 0
(-6000 1250);
DISPLAY 0.978723 (-6000 1250);
PAINT WHITE (-6000 1250);
DISPLAY INVISIBLE (-6000 1250);
FORCEPROP 1 LAST PART_NUMBER CS21001FE07
J 0
(-6000 1200);
DISPLAY 0.978723 (-6000 1200);
DISPLAY INVISIBLE (-6000 1200);
FORCEADD Q_RES..1
(-5950 1175);
FORCEPROP 1 LAST LOCATION R6766
J 0
(-6250 1175);
DISPLAY 0.978723 (-6250 1175);
PAINT SKYBLUE (-6250 1175);
FORCEPROP 0 LAST $SEC 1
J 0
(-5425 1225);
DISPLAY 0.680851 (-5425 1225);
PAINT MONO (-5425 1225);
DISPLAY INVISIBLE (-5425 1225);
FORCEPROP 0 LAST CDS_SEC 1
J 0
(-5425 1225);
DISPLAY 0.680851 (-5425 1225);
DISPLAY INVISIBLE (-5425 1225);
FORCEPROP 1 LASTPIN (-6050 1175) $PN 1
J 0
(-6038 1187);
DISPLAY 0.787234 (-6038 1187);
PAINT MONO (-6038 1187);
FORCEPROP 1 LASTPIN (-5850 1175) $PN 2
J 0
(-5888 1187);
DISPLAY 0.787234 (-5888 1187);
PAINT MONO (-5888 1187);
FORCEPROP 1 LAST PACK_TYPE 0201LF
J 0
(-5425 1175);
DISPLAY 0.978723 (-5425 1175);
FORCEPROP 1 LAST VALUE 1K
J 2
(-5675 1175);
DISPLAY 0.978723 (-5675 1175);
FORCEPROP 1 LAST MATERIAL CHIP
J 0
(-5650 1175);
DISPLAY 0.978723 (-5650 1175);
FORCEPROP 2 LAST CDS_LIB pure_quanta
J 0
(-5950 1175);
DISPLAY INVISIBLE (-5950 1175);
FORCEPROP 1 LAST TOLERANCE 1%
J 0
(-5975 1375);
DISPLAY 0.978723 (-5975 1375);
DISPLAY INVISIBLE (-5975 1375);
FORCEPROP 1 LAST WATTAGE 1/20W
J 2
(-5575 1375);
DISPLAY 0.978723 (-5575 1375);
DISPLAY INVISIBLE (-5575 1375);
FORCEPROP 1 LAST PATH I83
J 0
(-6000 1325);
DISPLAY 0.978723 (-6000 1325);
PAINT WHITE (-6000 1325);
DISPLAY INVISIBLE (-6000 1325);
FORCEPROP 1 LAST PART_NUMBER CS21001FE07
J 0
(-6000 1275);
DISPLAY 0.978723 (-6000 1275);
DISPLAY INVISIBLE (-6000 1275);
FORCEADD Q_RES..1
(-5950 1025);
FORCEPROP 1 LAST LOCATION R6768
J 0
(-6250 1025);
DISPLAY 0.978723 (-6250 1025);
PAINT SKYBLUE (-6250 1025);
FORCEPROP 0 LAST $SEC 1
J 0
(-5425 1075);
DISPLAY 0.680851 (-5425 1075);
PAINT MONO (-5425 1075);
DISPLAY INVISIBLE (-5425 1075);
FORCEPROP 0 LAST CDS_SEC 1
J 0
(-5425 1075);
DISPLAY 0.680851 (-5425 1075);
DISPLAY INVISIBLE (-5425 1075);
FORCEPROP 1 LASTPIN (-6050 1025) $PN 1
J 0
(-6038 1037);
DISPLAY 0.787234 (-6038 1037);
PAINT MONO (-6038 1037);
FORCEPROP 1 LASTPIN (-5850 1025) $PN 2
J 0
(-5888 1037);
DISPLAY 0.787234 (-5888 1037);
PAINT MONO (-5888 1037);
FORCEPROP 1 LAST VALUE 1K
J 2
(-5675 1025);
DISPLAY 0.978723 (-5675 1025);
FORCEPROP 1 LAST MATERIAL CHIP
J 0
(-5650 1025);
DISPLAY 0.978723 (-5650 1025);
FORCEPROP 1 LAST PACK_TYPE 0201LF
J 0
(-5425 1025);
DISPLAY 0.978723 (-5425 1025);
FORCEPROP 2 LAST CDS_LIB pure_quanta
J 0
(-5950 1025);
DISPLAY INVISIBLE (-5950 1025);
FORCEPROP 1 LAST TOLERANCE 1%
J 0
(-5975 1225);
DISPLAY 0.978723 (-5975 1225);
DISPLAY INVISIBLE (-5975 1225);
FORCEPROP 1 LAST WATTAGE 1/20W
J 2
(-5575 1225);
DISPLAY 0.978723 (-5575 1225);
DISPLAY INVISIBLE (-5575 1225);
FORCEPROP 1 LAST PATH I84
J 0
(-6000 1175);
DISPLAY 0.978723 (-6000 1175);
PAINT WHITE (-6000 1175);
DISPLAY INVISIBLE (-6000 1175);
FORCEPROP 1 LAST PART_NUMBER CS21001FE07
J 0
(-6000 1125);
DISPLAY 0.978723 (-6000 1125);
DISPLAY INVISIBLE (-6000 1125);
FORCEADD Q_RES..1
(-5950 950);
FORCEPROP 1 LAST LOCATION R6769
J 0
(-6250 950);
DISPLAY 0.978723 (-6250 950);
PAINT SKYBLUE (-6250 950);
FORCEPROP 0 LAST $SEC 1
J 0
(-5425 1000);
DISPLAY 0.680851 (-5425 1000);
PAINT MONO (-5425 1000);
DISPLAY INVISIBLE (-5425 1000);
FORCEPROP 0 LAST CDS_SEC 1
J 0
(-5425 1000);
DISPLAY 0.680851 (-5425 1000);
DISPLAY INVISIBLE (-5425 1000);
FORCEPROP 1 LASTPIN (-6050 950) $PN 1
J 0
(-6038 962);
DISPLAY 0.787234 (-6038 962);
PAINT MONO (-6038 962);
FORCEPROP 1 LASTPIN (-5850 950) $PN 2
J 0
(-5888 962);
DISPLAY 0.787234 (-5888 962);
PAINT MONO (-5888 962);
FORCEPROP 1 LAST VALUE 1K
J 2
(-5675 950);
DISPLAY 0.978723 (-5675 950);
FORCEPROP 1 LAST MATERIAL CHIP
J 0
(-5650 950);
DISPLAY 0.978723 (-5650 950);
FORCEPROP 1 LAST PACK_TYPE 0201LF
J 0
(-5425 950);
DISPLAY 0.978723 (-5425 950);
FORCEPROP 2 LAST CDS_LIB pure_quanta
J 0
(-5950 950);
DISPLAY INVISIBLE (-5950 950);
FORCEPROP 1 LAST WATTAGE 1/20W
J 2
(-5575 1150);
DISPLAY 0.978723 (-5575 1150);
DISPLAY INVISIBLE (-5575 1150);
FORCEPROP 1 LAST TOLERANCE 1%
J 0
(-5975 1150);
DISPLAY 0.978723 (-5975 1150);
DISPLAY INVISIBLE (-5975 1150);
FORCEPROP 1 LAST PATH I85
J 0
(-6000 1100);
DISPLAY 0.978723 (-6000 1100);
PAINT WHITE (-6000 1100);
DISPLAY INVISIBLE (-6000 1100);
FORCEPROP 1 LAST PART_NUMBER CS21001FE07
J 0
(-6000 1050);
DISPLAY 0.978723 (-6000 1050);
DISPLAY INVISIBLE (-6000 1050);
FORCEADD UNIVERSAL_GND..1
(-4250 3975);
FORCEPROP 3 LASTPIN (-4250 4025) SIG_NAME GND\g
J 0
(-4240 4035);
DISPLAY 0.659574 (-4240 4035);
PAINT MONO (-4240 4035);
DISPLAY INVISIBLE (-4240 4035);
FORCEPROP 2 LAST CDS_LIB pure_quanta_power
J 0
(-4250 3975);
DISPLAY INVISIBLE (-4250 3975);
FORCEPROP 1 LAST HDL_POWER GND
J 1
(-4225 3900);
DISPLAY 0.872340 (-4225 3900);
PAINT GREEN (-4225 3900);
DISPLAY INVISIBLE (-4225 3900);
FORCEPROP 1 LAST PATH I86
J 0
(-4175 3975);
DISPLAY 0.872340 (-4175 3975);
PAINT AQUA (-4175 3975);
DISPLAY INVISIBLE (-4175 3975);
FORCEADD P1V0_AUX..1
(-5475 5600);
FORCEPROP 3 LASTPIN (-5475 5550) SIG_NAME P1V8_AUX\g
J 0
(-5465 5560);
DISPLAY 0.659574 (-5465 5560);
PAINT MONO (-5465 5560);
DISPLAY INVISIBLE (-5465 5560);
FORCEPROP 1 LAST HDL_POWER P1V8_AUX
J 1
(-5465 5640);
DISPLAY 0.489362 (-5465 5640);
PAINT GREEN (-5465 5640);
FORCEPROP 2 LAST CDS_LIB pure_quanta_power
J 0
(-5475 5600);
DISPLAY INVISIBLE (-5475 5600);
FORCEPROP 1 LAST PATH I87
J 0
(-5425 5625);
DISPLAY 0.872340 (-5425 5625);
PAINT AQUA (-5425 5625);
DISPLAY INVISIBLE (-5425 5625);
FORCEADD Q_CAP..1
R 2
(-5650 5350);
FORCEPROP 1 LAST LOCATION C7500
J 2
(-5700 5450);
DISPLAY 0.638298 (-5700 5450);
FORCEPROP 0 LAST $SEC 1
J 0
(-5700 5500);
DISPLAY 0.680851 (-5700 5500);
PAINT MONO (-5700 5500);
DISPLAY INVISIBLE (-5700 5500);
FORCEPROP 0 LAST CDS_SEC 1
J 0
(-5700 5500);
DISPLAY 0.680851 (-5700 5500);
DISPLAY INVISIBLE (-5700 5500);
FORCEPROP 1 LASTPIN (-5650 5450) $PN 1
J 2
(-5660 5430);
DISPLAY 0.787234 (-5660 5430);
PAINT MONO (-5660 5430);
FORCEPROP 1 LASTPIN (-5650 5250) $PN 2
J 2
(-5660 5230);
DISPLAY 0.787234 (-5660 5230);
PAINT MONO (-5660 5230);
FORCEPROP 1 LAST VOLTAGE 10V
J 2
(-5700 5350);
DISPLAY 0.638298 (-5700 5350);
FORCEPROP 1 LAST TOLERANCE 10%
J 2
(-5700 5300);
DISPLAY 0.638298 (-5700 5300);
FORCEPROP 1 LAST MATERIAL X7S
J 2
(-5700 5250);
DISPLAY 0.638298 (-5700 5250);
FORCEPROP 1 LAST VALUE 0.1UF
J 2
(-5700 5400);
DISPLAY 0.638298 (-5700 5400);
FORCEPROP 1 LAST PACK_TYPE C0201
J 2
(-5700 5150);
DISPLAY 0.638298 (-5700 5150);
FORCEPROP 2 LAST CDS_LIB pure_quanta
J 2
(-5650 5350);
DISPLAY INVISIBLE (-5650 5350);
FORCEPROP 1 LAST PATH I88
J 2
(-5700 5500);
DISPLAY 0.978723 (-5700 5500);
PAINT WHITE (-5700 5500);
DISPLAY INVISIBLE (-5700 5500);
FORCEPROP 1 LAST PART_NUMBER CH4102K6E00
J 2
(-5700 5200);
DISPLAY 0.638298 (-5700 5200);
DISPLAY INVISIBLE (-5700 5200);
FORCEADD UNIVERSAL_GND..1
(-5650 5050);
FORCEPROP 3 LASTPIN (-5650 5100) SIG_NAME GND\g
J 0
(-5640 5110);
DISPLAY 0.659574 (-5640 5110);
PAINT MONO (-5640 5110);
DISPLAY INVISIBLE (-5640 5110);
FORCEPROP 2 LAST CDS_LIB pure_quanta_power
J 0
(-5650 5050);
DISPLAY INVISIBLE (-5650 5050);
FORCEPROP 1 LAST HDL_POWER GND
J 1
(-5625 4975);
DISPLAY 0.872340 (-5625 4975);
PAINT GREEN (-5625 4975);
DISPLAY INVISIBLE (-5625 4975);
FORCEPROP 1 LAST PATH I89
J 0
(-5575 5050);
DISPLAY 0.872340 (-5575 5050);
PAINT AQUA (-5575 5050);
DISPLAY INVISIBLE (-5575 5050);
FORCEADD Q_RES..1
(-2625 1450);
FORCEPROP 1 LAST LOCATION R6718
J 0
(-2925 1450);
DISPLAY 0.978723 (-2925 1450);
PAINT SKYBLUE (-2925 1450);
FORCEPROP 0 LAST $SEC 1
J 0
(-2250 1700);
DISPLAY 0.680851 (-2250 1700);
PAINT MONO (-2250 1700);
DISPLAY INVISIBLE (-2250 1700);
FORCEPROP 0 LAST CDS_SEC 1
J 0
(-2250 1700);
DISPLAY 0.680851 (-2250 1700);
DISPLAY INVISIBLE (-2250 1700);
FORCEPROP 1 LASTPIN (-2725 1450) $PN 1
J 0
(-2713 1462);
DISPLAY 0.787234 (-2713 1462);
PAINT MONO (-2713 1462);
FORCEPROP 1 LASTPIN (-2525 1450) $PN 2
J 0
(-2563 1462);
DISPLAY 0.787234 (-2563 1462);
PAINT MONO (-2563 1462);
FORCEPROP 1 LAST TOLERANCE 1%
J 0
(-2650 1650);
DISPLAY 0.978723 (-2650 1650);
FORCEPROP 1 LAST WATTAGE 1/20W
J 2
(-2250 1650);
DISPLAY 0.978723 (-2250 1650);
FORCEPROP 1 LAST PACK_TYPE 0201LF
J 0
(-2100 1450);
DISPLAY 0.978723 (-2100 1450);
FORCEPROP 1 LAST MATERIAL CHIP
J 0
(-2325 1450);
DISPLAY 0.978723 (-2325 1450);
FORCEPROP 1 LAST VALUE 1K
J 2
(-2350 1450);
DISPLAY 0.978723 (-2350 1450);
FORCEPROP 2 LAST CDS_LIB pure_quanta
J 0
(-2625 1450);
DISPLAY INVISIBLE (-2625 1450);
FORCEPROP 1 LAST PATH I9
J 0
(-2675 1600);
DISPLAY 0.978723 (-2675 1600);
PAINT WHITE (-2675 1600);
DISPLAY INVISIBLE (-2675 1600);
FORCEPROP 1 LAST PART_NUMBER CS21001FE07
J 0
(-2675 1550);
DISPLAY 0.978723 (-2675 1550);
DISPLAY INVISIBLE (-2675 1550);
FORCEADD OFFPAGE..1
(-6250 4900);
FORCEPROP 2 LAST $XR0 184 
J 0
(-6532 4900);
DISPLAY 0.638298 (-6532 4900);
PAINT MONO (-6532 4900);
FORCEPROP 2 LAST CDS_LIB standard
J 0
(-6250 4900);
DISPLAY INVISIBLE (-6250 4900);
FORCEPROP 1 LAST OFFPAGE TRUE
J 0
(-5925 4775);
DISPLAY 1.170213 (-5925 4775);
PAINT GREEN (-5925 4775);
DISPLAY INVISIBLE (-5925 4775);
FORCEPROP 1 LAST COMMENT_BODY TRUE
J 0
(-6125 4800);
DISPLAY 1.170213 (-6125 4800);
PAINT GREEN (-6125 4800);
DISPLAY INVISIBLE (-6125 4800);
FORCEPROP 2 LAST PATH I90
J 0
(-6200 4975);
DISPLAY 0.680851 (-6200 4975);
DISPLAY INVISIBLE (-6200 4975);
FORCEADD OFFPAGE..1
(-6250 4850);
FORCEPROP 2 LAST $XR0 184 
J 0
(-6532 4850);
DISPLAY 0.638298 (-6532 4850);
PAINT MONO (-6532 4850);
FORCEPROP 2 LAST CDS_LIB standard
J 0
(-6250 4850);
DISPLAY INVISIBLE (-6250 4850);
FORCEPROP 1 LAST OFFPAGE TRUE
J 0
(-5925 4725);
DISPLAY 1.170213 (-5925 4725);
PAINT GREEN (-5925 4725);
DISPLAY INVISIBLE (-5925 4725);
FORCEPROP 1 LAST COMMENT_BODY TRUE
J 0
(-6125 4750);
DISPLAY 1.170213 (-6125 4750);
PAINT GREEN (-6125 4750);
DISPLAY INVISIBLE (-6125 4750);
FORCEPROP 2 LAST PATH I91
J 0
(-6200 4925);
DISPLAY 0.680851 (-6200 4925);
DISPLAY INVISIBLE (-6200 4925);
FORCEADD OFFPAGE..1
(-6250 4800);
FORCEPROP 2 LAST $XR0 184 
J 0
(-6532 4800);
DISPLAY 0.638298 (-6532 4800);
PAINT MONO (-6532 4800);
FORCEPROP 2 LAST CDS_LIB standard
J 0
(-6250 4800);
DISPLAY INVISIBLE (-6250 4800);
FORCEPROP 1 LAST OFFPAGE TRUE
J 0
(-5925 4675);
DISPLAY 1.170213 (-5925 4675);
PAINT GREEN (-5925 4675);
DISPLAY INVISIBLE (-5925 4675);
FORCEPROP 1 LAST COMMENT_BODY TRUE
J 0
(-6125 4700);
DISPLAY 1.170213 (-6125 4700);
PAINT GREEN (-6125 4700);
DISPLAY INVISIBLE (-6125 4700);
FORCEPROP 2 LAST PATH I92
J 0
(-6200 4875);
DISPLAY 0.680851 (-6200 4875);
DISPLAY INVISIBLE (-6200 4875);
FORCEADD UNIVERSAL_GND..1
(-8600 600);
FORCEPROP 3 LASTPIN (-8600 650) SIG_NAME GND\g
J 0
(-8590 660);
DISPLAY 0.659574 (-8590 660);
PAINT MONO (-8590 660);
DISPLAY INVISIBLE (-8590 660);
FORCEPROP 2 LAST CDS_LIB pure_quanta_power
J 0
(-8600 600);
DISPLAY INVISIBLE (-8600 600);
FORCEPROP 1 LAST HDL_POWER GND
J 1
(-8575 525);
DISPLAY 0.872340 (-8575 525);
PAINT GREEN (-8575 525);
DISPLAY INVISIBLE (-8575 525);
FORCEPROP 1 LAST PATH I93
J 0
(-8525 600);
DISPLAY 0.872340 (-8525 600);
PAINT AQUA (-8525 600);
DISPLAY INVISIBLE (-8525 600);
FORCEADD Q_RES..2
(-8600 1025);
FORCEPROP 1 LAST LOCATION R6773
J 0
(-8555 1150);
DISPLAY 0.787234 (-8555 1150);
FORCEPROP 0 LAST $SEC 1
J 0
(-8550 1200);
DISPLAY 0.680851 (-8550 1200);
PAINT MONO (-8550 1200);
DISPLAY INVISIBLE (-8550 1200);
FORCEPROP 0 LAST CDS_SEC 1
J 0
(-8550 1200);
DISPLAY 0.680851 (-8550 1200);
DISPLAY INVISIBLE (-8550 1200);
FORCEPROP 1 LASTPIN (-8600 1125) $PN 1
J 0
(-8595 1087);
DISPLAY 0.787234 (-8595 1087);
PAINT MONO (-8595 1087);
FORCEPROP 1 LASTPIN (-8600 925) $PN 2
J 0
(-8595 935);
DISPLAY 0.787234 (-8595 935);
PAINT MONO (-8595 935);
FORCEPROP 1 LAST WATTAGE 1/20W
J 0
(-8560 1000);
DISPLAY 0.787234 (-8560 1000);
FORCEPROP 1 LAST TOLERANCE 5%
J 0
(-8555 1050);
DISPLAY 0.787234 (-8555 1050);
FORCEPROP 1 LAST PACK_TYPE 0201LF
J 0
(-8560 850);
DISPLAY 0.787234 (-8560 850);
FORCEPROP 1 LAST VALUE 4.7K
J 0
(-8555 1100);
DISPLAY 0.787234 (-8555 1100);
FORCEPROP 1 LAST MATERIAL CHIP
J 0
(-8560 950);
DISPLAY 0.787234 (-8560 950);
FORCEPROP 2 LAST CDS_LIB pure_quanta
J 0
(-8600 1025);
DISPLAY INVISIBLE (-8600 1025);
FORCEPROP 1 LAST PATH I94
J 0
(-8550 1200);
DISPLAY 0.978723 (-8550 1200);
PAINT WHITE (-8550 1200);
DISPLAY INVISIBLE (-8550 1200);
FORCEPROP 1 LAST PART_NUMBER CS24701JE04
J 0
(-8560 900);
DISPLAY 0.978723 (-8560 900);
DISPLAY INVISIBLE (-8560 900);
FORCEADD Q_RES..2
(-8300 1025);
FORCEPROP 1 LAST LOCATION R6774
J 0
(-8255 1150);
DISPLAY 0.787234 (-8255 1150);
FORCEPROP 0 LAST $SEC 1
J 0
(-8250 1200);
DISPLAY 0.680851 (-8250 1200);
PAINT MONO (-8250 1200);
DISPLAY INVISIBLE (-8250 1200);
FORCEPROP 0 LAST CDS_SEC 1
J 0
(-8250 1200);
DISPLAY 0.680851 (-8250 1200);
DISPLAY INVISIBLE (-8250 1200);
FORCEPROP 1 LASTPIN (-8300 1125) $PN 1
J 0
(-8295 1087);
DISPLAY 0.787234 (-8295 1087);
PAINT MONO (-8295 1087);
FORCEPROP 1 LASTPIN (-8300 925) $PN 2
J 0
(-8295 935);
DISPLAY 0.787234 (-8295 935);
PAINT MONO (-8295 935);
FORCEPROP 1 LAST VALUE 4.7K
J 0
(-8255 1100);
DISPLAY 0.787234 (-8255 1100);
FORCEPROP 1 LAST TOLERANCE 5%
J 0
(-8255 1050);
DISPLAY 0.787234 (-8255 1050);
FORCEPROP 1 LAST PACK_TYPE 0201LF
J 0
(-8260 850);
DISPLAY 0.787234 (-8260 850);
FORCEPROP 1 LAST MATERIAL CHIP
J 0
(-8260 950);
DISPLAY 0.787234 (-8260 950);
FORCEPROP 1 LAST WATTAGE 1/20W
J 0
(-8260 1000);
DISPLAY 0.787234 (-8260 1000);
FORCEPROP 2 LAST CDS_LIB pure_quanta
J 0
(-8300 1025);
DISPLAY INVISIBLE (-8300 1025);
FORCEPROP 1 LAST PATH I95
J 0
(-8250 1200);
DISPLAY 0.978723 (-8250 1200);
PAINT WHITE (-8250 1200);
DISPLAY INVISIBLE (-8250 1200);
FORCEPROP 1 LAST PART_NUMBER CS24701JE04
J 0
(-8260 900);
DISPLAY 0.978723 (-8260 900);
DISPLAY INVISIBLE (-8260 900);
FORCEADD Q_RES..2
(-8600 1800);
FORCEPROP 1 LAST LOCATION R6770
J 0
(-8555 1925);
DISPLAY 0.787234 (-8555 1925);
FORCEPROP 0 LAST $SEC 1
J 0
(-8550 1975);
DISPLAY 0.680851 (-8550 1975);
PAINT MONO (-8550 1975);
DISPLAY INVISIBLE (-8550 1975);
FORCEPROP 0 LAST CDS_SEC 1
J 0
(-8550 1975);
DISPLAY 0.680851 (-8550 1975);
DISPLAY INVISIBLE (-8550 1975);
FORCEPROP 1 LASTPIN (-8600 1900) $PN 1
J 0
(-8595 1862);
DISPLAY 0.787234 (-8595 1862);
PAINT MONO (-8595 1862);
FORCEPROP 1 LASTPIN (-8600 1700) $PN 2
J 0
(-8595 1710);
DISPLAY 0.787234 (-8595 1710);
PAINT MONO (-8595 1710);
FORCEPROP 1 LAST PACK_TYPE 0201LF
J 0
(-8550 1650);
DISPLAY 0.787234 (-8550 1650);
FORCEPROP 1 LAST TOLERANCE 5%
J 0
(-8555 1825);
DISPLAY 0.787234 (-8555 1825);
FORCEPROP 1 LAST WATTAGE 1/20W
J 0
(-8560 1775);
DISPLAY 0.787234 (-8560 1775);
FORCEPROP 1 LAST VALUE 4.7K
J 0
(-8555 1875);
DISPLAY 0.787234 (-8555 1875);
FORCEPROP 1 LAST MATERIAL EMPTY
J 0
(-8560 1725);
DISPLAY 0.787234 (-8560 1725);
FORCEPROP 2 LAST CDS_LIB pure_quanta
J 0
(-8600 1800);
DISPLAY INVISIBLE (-8600 1800);
FORCEPROP 1 LAST PATH I96
J 0
(-8550 1975);
DISPLAY 0.978723 (-8550 1975);
PAINT WHITE (-8550 1975);
DISPLAY INVISIBLE (-8550 1975);
FORCEPROP 1 LAST PART_NUMBER CS24701JE04
J 0
(-8560 1675);
DISPLAY 0.978723 (-8560 1675);
DISPLAY INVISIBLE (-8560 1675);
FORCEADD Q_RES..2
(-7950 1025);
FORCEPROP 1 LAST LOCATION R6775
J 0
(-7905 1150);
DISPLAY 0.787234 (-7905 1150);
FORCEPROP 0 LAST $SEC 1
J 0
(-7900 1200);
DISPLAY 0.680851 (-7900 1200);
PAINT MONO (-7900 1200);
DISPLAY INVISIBLE (-7900 1200);
FORCEPROP 0 LAST CDS_SEC 1
J 0
(-7900 1200);
DISPLAY 0.680851 (-7900 1200);
DISPLAY INVISIBLE (-7900 1200);
FORCEPROP 1 LASTPIN (-7950 1125) $PN 1
J 0
(-7945 1087);
DISPLAY 0.787234 (-7945 1087);
PAINT MONO (-7945 1087);
FORCEPROP 1 LASTPIN (-7950 925) $PN 2
J 0
(-7945 935);
DISPLAY 0.787234 (-7945 935);
PAINT MONO (-7945 935);
FORCEPROP 1 LAST VALUE 4.7K
J 0
(-7905 1100);
DISPLAY 0.787234 (-7905 1100);
FORCEPROP 1 LAST PACK_TYPE 0201LF
J 0
(-7910 850);
DISPLAY 0.787234 (-7910 850);
FORCEPROP 1 LAST MATERIAL CHIP
J 0
(-7910 950);
DISPLAY 0.787234 (-7910 950);
FORCEPROP 1 LAST WATTAGE 1/20W
J 0
(-7910 1000);
DISPLAY 0.787234 (-7910 1000);
FORCEPROP 1 LAST TOLERANCE 5%
J 0
(-7905 1050);
DISPLAY 0.787234 (-7905 1050);
FORCEPROP 2 LAST CDS_LIB pure_quanta
J 0
(-7950 1025);
DISPLAY INVISIBLE (-7950 1025);
FORCEPROP 1 LAST PATH I97
J 0
(-7900 1200);
DISPLAY 0.978723 (-7900 1200);
PAINT WHITE (-7900 1200);
DISPLAY INVISIBLE (-7900 1200);
FORCEPROP 1 LAST PART_NUMBER CS24701JE04
J 0
(-7910 900);
DISPLAY 0.978723 (-7910 900);
DISPLAY INVISIBLE (-7910 900);
FORCEADD Q_RES..2
(-7950 1775);
FORCEPROP 1 LAST LOCATION R6772
J 0
(-7905 1900);
DISPLAY 0.787234 (-7905 1900);
FORCEPROP 0 LAST $SEC 1
J 0
(-7900 1950);
DISPLAY 0.680851 (-7900 1950);
PAINT MONO (-7900 1950);
DISPLAY INVISIBLE (-7900 1950);
FORCEPROP 0 LAST CDS_SEC 1
J 0
(-7900 1950);
DISPLAY 0.680851 (-7900 1950);
DISPLAY INVISIBLE (-7900 1950);
FORCEPROP 1 LASTPIN (-7950 1875) $PN 1
J 0
(-7945 1837);
DISPLAY 0.787234 (-7945 1837);
PAINT MONO (-7945 1837);
FORCEPROP 1 LASTPIN (-7950 1675) $PN 2
J 0
(-7945 1685);
DISPLAY 0.787234 (-7945 1685);
PAINT MONO (-7945 1685);
FORCEPROP 1 LAST VALUE 4.7K
J 0
(-7905 1850);
DISPLAY 0.787234 (-7905 1850);
FORCEPROP 1 LAST WATTAGE 1/20W
J 0
(-7910 1750);
DISPLAY 0.787234 (-7910 1750);
FORCEPROP 1 LAST TOLERANCE 5%
J 0
(-7905 1800);
DISPLAY 0.787234 (-7905 1800);
FORCEPROP 1 LAST PACK_TYPE 0201LF
J 0
(-7900 1625);
DISPLAY 0.787234 (-7900 1625);
FORCEPROP 1 LAST MATERIAL EMPTY
J 0
(-7910 1700);
DISPLAY 0.787234 (-7910 1700);
FORCEPROP 2 LAST CDS_LIB pure_quanta
J 0
(-7950 1775);
DISPLAY INVISIBLE (-7950 1775);
FORCEPROP 1 LAST PATH I98
J 0
(-7900 1950);
DISPLAY 0.978723 (-7900 1950);
PAINT WHITE (-7900 1950);
DISPLAY INVISIBLE (-7900 1950);
FORCEPROP 1 LAST PART_NUMBER CS24701JE04
J 0
(-7910 1650);
DISPLAY 0.978723 (-7910 1650);
DISPLAY INVISIBLE (-7910 1650);
FORCEADD DNS..1
(-8175 1675);
PAINT RED (-8175 1675);
FORCEPROP 2 LAST CDS_LIB mstr_misc
J 0
(-8175 1675);
DISPLAY INVISIBLE (-8175 1675);
FORCEPROP 1 LAST COMMENT_BODY TRUE
R 1
J 0
(-8100 1450);
DISPLAY 0.872340 (-8100 1450);
PAINT GREEN (-8100 1450);
DISPLAY INVISIBLE (-8100 1450);
FORCEADD DNS..1
(-8525 1700);
PAINT RED (-8525 1700);
FORCEPROP 2 LAST CDS_LIB mstr_misc
J 0
(-8525 1700);
DISPLAY INVISIBLE (-8525 1700);
FORCEPROP 1 LAST COMMENT_BODY TRUE
R 1
J 0
(-8450 1475);
DISPLAY 0.872340 (-8450 1475);
PAINT GREEN (-8450 1475);
DISPLAY INVISIBLE (-8450 1475);
FORCEADD QUANTA_TITLE_BLOCK_C..1
(0 0);
FORCEPROP 0 LAST CDS_CON_LAST_MODIFIED Thu Sep 14 16:13:03 2023
J 0
(-1885 15);
DISPLAY INVISIBLE (-1885 15);
FORCEPROP 1 LAST CUSTOM_TXT_CDS <CON_LAST_MODIFIED>
J 0
(-1885 15);
DISPLAY 0.978723 (-1885 15);
FORCEPROP 2 LAST CUSTOM_TXT_CDS <XR_PAGE_TITLE>
J 0
(-7890 5250);
DISPLAY 0.638298 (-7890 5250);
PAINT PINK (-7890 5250);
DISPLAY INVISIBLE (-7890 5250);
FORCEPROP 1 LAST CUSTOM_TXT_CDS <NAME_2>
J 0
(-3175 50);
FORCEPROP 1 LAST CUSTOM_TXT_CDS <NAME_1>
J 0
(-3175 175);
FORCEPROP 1 LAST CUSTOM_TXT_CDS <Q_NUMBER>
J 0
(-1403 103);
DISPLAY 1.212766 (-1403 103);
FORCEPROP 1 LAST CUSTOM_TXT_CDS <Q_PROJ>
J 0
(-2382 102);
DISPLAY 1.212766 (-2382 102);
FORCEPROP 1 LAST CUSTOM_TXT_CDS <Q_REV>
J 0
(-184 103);
DISPLAY 1.212766 (-184 103);
FORCEPROP 1 LAST CUSTOM_TXT_CDS <CON_PAGE_NUM> OF <CON_TOTAL_PAGES>
J 0
(-446 18);
DISPLAY 0.978723 (-446 18);
FORCEPROP 1 LAST Q_TITLE SMBUS - RETIMER
J 0
(-9366 26);
DISPLAY 2.446809 (-9366 26);
PAINT GREEN (-9366 26);
FORCEPROP 2 LAST CDS_LIB pure_quanta
J 0
(0 0);
DISPLAY INVISIBLE (0 0);
FORCEPROP 1 LAST CDS_LMAN_SYM_OUTLINE -9475,6775,100,-125
J 0
(0 0);
DISPLAY 0.468085 (0 0);
PAINT GREEN (0 0);
DISPLAY INVISIBLE (0 0);
FORCEPROP 2 LAST PAGE_BORDER TRUE
J 0
(-7890 5250);
DISPLAY 0.638298 (-7890 5250);
PAINT PINK (-7890 5250);
DISPLAY INVISIBLE (-7890 5250);
FORCEPROP 2 LAST CDS_XR_PAGE_TITLE CR-184 : @T6G_MB_LIB.T6G(SCH_1):PAGE184
J 0
(-7890 5250);
DISPLAY 0.638298 (-7890 5250);
PAINT PINK (-7890 5250);
DISPLAY INVISIBLE (-7890 5250);
FORCEPROP 1 LAST Q_DEPT BU9
J 1
(-3763 49);
DISPLAY 1.957447 (-3763 49);
PAINT GREEN (-3763 49);
DISPLAY INVISIBLE (-3763 49);
FORCEPROP 1 LAST COMMENT_BODY TRUE
J 0
(12 -13);
DISPLAY 0.978723 (12 -13);
PAINT GREEN (12 -13);
DISPLAY INVISIBLE (12 -13);
FORCEADD DNS..1
(-7850 1700);
PAINT RED (-7850 1700);
FORCEPROP 2 LAST CDS_LIB mstr_misc
J 0
(-7850 1700);
DISPLAY INVISIBLE (-7850 1700);
FORCEPROP 1 LAST COMMENT_BODY TRUE
R 1
J 0
(-7775 1475);
DISPLAY 0.872340 (-7775 1475);
PAINT GREEN (-7775 1475);
DISPLAY INVISIBLE (-7775 1475);
WIRE 16 -1 (-6975 2900)(-6975 2375);
WIRE 16 -1 (-1000 5400)(-1225 5400);
WIRE 16 -1 (-1225 5400)(-1225 5275);
WIRE 16 -1 (-4550 4150)(-4250 4150);
WIRE 16 -1 (-4250 4150)(-4250 4025);
WIRE 16 -1 (-5650 5250)(-5650 5100);
WIRE 16 -1 (-6975 3275)(-6975 3100);
WIRE 16 -1 (-7950 3275)(-6975 3275);
FORCEPROP 2 LAST SIG_NAME RST_SMB_RT_R1_N
J 0
(-7760 3310);
DISPLAY 0.680851 (-7760 3310);
WIRE 16 -1 (-4550 4800)(-3150 4800);
FORCEPROP 2 LAST SIG_NAME SMB_MUX_RT_SCL
J 0
(-4260 4810);
DISPLAY 0.680851 (-4260 4810);
FORCEPROP 2 LASTPROP $XRERR UNIQUE?
J 0
(-4500 4810);
DISPLAY 0.638298 (-4500 4810);
PAINT MONO (-4500 4810);
DISPLAY INVISIBLE (-4500 4810);
WIRE 16 -1 (-2950 4800)(-2675 4800);
WIRE 16 -1 (-2675 4800)(-1775 4800);
FORCEPROP 2 LAST SIG_NAME SMB_MUX_RT_R1_SCL
J 0
(-2535 4810);
DISPLAY 0.680851 (-2535 4810);
WIRE 16 -1 (-2675 5500)(-2675 4800);
WIRE 16 -1 (-2250 5500)(-2675 5500);
WIRE 16 -1 (-4550 4850)(-3150 4850);
FORCEPROP 2 LAST SIG_NAME SMB_MUX_RT_SDA
J 0
(-4260 4860);
DISPLAY 0.680851 (-4260 4860);
FORCEPROP 2 LASTPROP $XRERR UNIQUE?
J 0
(-4500 4860);
DISPLAY 0.638298 (-4500 4860);
PAINT MONO (-4500 4860);
DISPLAY INVISIBLE (-4500 4860);
WIRE 16 -1 (-2950 4850)(-2575 4850);
WIRE 16 -1 (-2575 4850)(-1775 4850);
FORCEPROP 2 LAST SIG_NAME SMB_MUX_RT_R1_SDA
J 0
(-2535 4860);
DISPLAY 0.680851 (-2535 4860);
WIRE 16 -1 (-2575 5450)(-2575 4850);
WIRE 16 -1 (-2250 5450)(-2575 5450);
WIRE 16 -1 (-1725 4550)(-3000 4550);
FORCEPROP 2 LAST SIG_NAME SMB_RT_CPU0_P0_R_SCL
J 0
(-2760 4560);
DISPLAY 0.680851 (-2760 4560);
WIRE 16 -1 (-3200 4500)(-4550 4500);
FORCEPROP 2 LAST SIG_NAME SMB_RT_CPU0_P1_SDA
J 0
(-4285 4510);
DISPLAY 0.680851 (-4285 4510);
FORCEPROP 2 LASTPROP $XRERR UNIQUE?
J 0
(-4525 4510);
DISPLAY 0.638298 (-4525 4510);
PAINT MONO (-4525 4510);
DISPLAY INVISIBLE (-4525 4510);
WIRE 16 -1 (-3200 4550)(-4550 4550);
FORCEPROP 2 LAST SIG_NAME SMB_RT_CPU0_P0_SCL
J 0
(-4285 4560);
DISPLAY 0.680851 (-4285 4560);
FORCEPROP 2 LASTPROP $XRERR UNIQUE?
J 0
(-4525 4560);
DISPLAY 0.638298 (-4525 4560);
PAINT MONO (-4525 4560);
DISPLAY INVISIBLE (-4525 4560);
WIRE 16 -1 (-3200 4600)(-4550 4600);
FORCEPROP 2 LAST SIG_NAME SMB_RT_CPU0_P0_SDA
J 0
(-4285 4610);
DISPLAY 0.680851 (-4285 4610);
FORCEPROP 2 LASTPROP $XRERR UNIQUE?
J 0
(-4525 4610);
DISPLAY 0.638298 (-4525 4610);
PAINT MONO (-4525 4610);
DISPLAY INVISIBLE (-4525 4610);
WIRE 16 -1 (-2050 5450)(-1000 5450);
FORCEPROP 2 LAST SIG_NAME SMB_MUX_RT_R2_SDA
J 0
(-1735 5460);
DISPLAY 0.680851 (-1735 5460);
FORCEPROP 2 LASTPROP $XRERR UNIQUE?
J 0
(-1975 5460);
DISPLAY 0.638298 (-1975 5460);
PAINT MONO (-1975 5460);
DISPLAY INVISIBLE (-1975 5460);
WIRE 16 -1 (-1750 4600)(-3000 4600);
FORCEPROP 2 LAST SIG_NAME SMB_RT_CPU0_P0_R_SDA
J 0
(-2785 4610);
DISPLAY 0.680851 (-2785 4610);
WIRE 16 -1 (-1750 4500)(-3000 4500);
FORCEPROP 2 LAST SIG_NAME SMB_RT_CPU0_P1_R_SDA
J 0
(-2785 4510);
DISPLAY 0.680851 (-2785 4510);
WIRE 16 -1 (-1750 4450)(-3000 4450);
FORCEPROP 2 LAST SIG_NAME SMB_RT_CPU0_P1_R_SCL
J 0
(-2760 4460);
DISPLAY 0.680851 (-2760 4460);
WIRE 16 -1 (-1750 4350)(-3000 4350);
FORCEPROP 2 LAST SIG_NAME SMB_RT_CPU0_P3_R_SCL
J 0
(-2760 4360);
DISPLAY 0.680851 (-2760 4360);
WIRE 16 -1 (-1750 4250)(-3000 4250);
FORCEPROP 2 LAST SIG_NAME SMB_RT_CPU0_P2_R_SCL
J 0
(-2760 4260);
DISPLAY 0.680851 (-2760 4260);
WIRE 16 -1 (-2050 5500)(-1000 5500);
FORCEPROP 2 LAST SIG_NAME SMB_MUX_RT_R2_SCL
J 0
(-1735 5510);
DISPLAY 0.680851 (-1735 5510);
FORCEPROP 2 LASTPROP $XRERR UNIQUE?
J 0
(-1975 5510);
DISPLAY 0.638298 (-1975 5510);
PAINT MONO (-1975 5510);
DISPLAY INVISIBLE (-1975 5510);
WIRE 16 -1 (-7950 925)(-7950 750);
WIRE 16 -1 (-7950 750)(-8300 750);
WIRE 16 -1 (-8300 925)(-8300 750);
WIRE 16 -1 (-8300 750)(-8600 750);
WIRE 16 -1 (-8600 925)(-8600 750);
WIRE 16 -1 (-8600 750)(-8600 650);
WIRE 16 -1 (-5475 5550)(-5475 5525);
WIRE 16 -1 (-5650 5525)(-5475 5525);
WIRE 16 -1 (-5475 5525)(-5475 5000);
WIRE 16 -1 (-5475 5000)(-5250 5000);
WIRE 16 -1 (-5650 5450)(-5650 5525);
WIRE 16 -1 (-6475 950)(-6050 950);
WIRE 16 -1 (-6475 1025)(-6475 950);
WIRE 16 -1 (-6475 1025)(-6050 1025);
WIRE 16 -1 (-6475 1100)(-6475 1025);
WIRE 16 -1 (-6475 1100)(-6050 1100);
WIRE 16 -1 (-6475 1175)(-6475 1100);
WIRE 16 -1 (-6475 1175)(-6050 1175);
WIRE 16 -1 (-6475 1275)(-6475 1175);
WIRE 16 -1 (-6475 1275)(-6050 1275);
WIRE 16 -1 (-6475 1275)(-6475 1350);
WIRE 16 -1 (-6475 1350)(-6050 1350);
WIRE 16 -1 (-6475 1425)(-6475 1350);
WIRE 16 -1 (-6475 1425)(-6050 1425);
WIRE 16 -1 (-6475 1525)(-6475 1425);
WIRE 16 -1 (-6475 1525)(-6050 1525);
WIRE 16 -1 (-6475 1775)(-6475 1525);
WIRE 16 -1 (-3150 875)(-2725 875);
WIRE 16 -1 (-3150 950)(-3150 875);
WIRE 16 -1 (-3150 950)(-2725 950);
WIRE 16 -1 (-3150 1025)(-3150 950);
WIRE 16 -1 (-3150 1025)(-2725 1025);
WIRE 16 -1 (-3150 1100)(-3150 1025);
WIRE 16 -1 (-3150 1100)(-2725 1100);
WIRE 16 -1 (-3150 1200)(-3150 1100);
WIRE 16 -1 (-3150 1200)(-2725 1200);
WIRE 16 -1 (-3150 1200)(-3150 1275);
WIRE 16 -1 (-3150 1275)(-2725 1275);
WIRE 16 -1 (-3150 1350)(-3150 1275);
WIRE 16 -1 (-3150 1350)(-2725 1350);
WIRE 16 -1 (-3150 1450)(-3150 1350);
WIRE 16 -1 (-3150 1450)(-2725 1450);
WIRE 16 -1 (-3150 1700)(-3150 1450);
WIRE 16 -1 (-8300 2125)(-7950 2125);
WIRE 16 -1 (-8600 2125)(-8300 2125);
WIRE 16 -1 (-8300 2125)(-8300 1900);
WIRE 16 -1 (-7950 2125)(-7950 1875);
WIRE 16 -1 (-8600 1900)(-8600 2125);
WIRE 16 -1 (-8600 2125)(-8600 2175);
WIRE 16 -1 (-1750 4300)(-3000 4300);
FORCEPROP 2 LAST SIG_NAME SMB_RT_CPU0_P2_R_SDA
J 0
(-2785 4310);
DISPLAY 0.680851 (-2785 4310);
WIRE 16 -1 (-1750 4400)(-3000 4400);
FORCEPROP 2 LAST SIG_NAME SMB_RT_CPU0_P3_R_SDA
J 0
(-2785 4410);
DISPLAY 0.680851 (-2785 4410);
WIRE 16 -1 (-6450 4400)(-7675 4400);
FORCEPROP 2 LAST SIG_NAME SMB_RT_CPU1_P3_R_SDA
J 0
(-7610 4410);
DISPLAY 0.680851 (-7610 4410);
WIRE 16 -1 (-6450 4350)(-7700 4350);
FORCEPROP 2 LAST SIG_NAME SMB_RT_CPU1_P3_R_SCL
J 0
(-7610 4360);
DISPLAY 0.680851 (-7610 4360);
WIRE 16 -1 (-6450 4250)(-7700 4250);
FORCEPROP 2 LAST SIG_NAME SMB_RT_CPU1_P2_R_SCL
J 0
(-7610 4260);
DISPLAY 0.680851 (-7610 4260);
WIRE 16 -1 (-6450 4450)(-7700 4450);
FORCEPROP 2 LAST SIG_NAME SMB_RT_CPU1_P1_R_SCL
J 0
(-7610 4460);
DISPLAY 0.680851 (-7610 4460);
PAINT SKYBLUE (-7610 4460);
WIRE 16 -1 (-2525 1450)(-825 1450);
FORCEPROP 2 LAST SIG_NAME SMB_RT_CPU1_P0_R_SDA
J 0
(-1585 1460);
DISPLAY 0.680851 (-1585 1460);
PAINT SKYBLUE (-1585 1460);
WIRE 16 -1 (-2525 1350)(-825 1350);
FORCEPROP 2 LAST SIG_NAME SMB_RT_CPU1_P0_R_SCL
J 0
(-1610 1360);
DISPLAY 0.680851 (-1610 1360);
PAINT SKYBLUE (-1610 1360);
WIRE 16 -1 (-2525 1275)(-825 1275);
FORCEPROP 2 LAST SIG_NAME SMB_RT_CPU1_P1_R_SDA
J 0
(-1610 1285);
DISPLAY 0.680851 (-1610 1285);
PAINT SKYBLUE (-1610 1285);
WIRE 16 -1 (-2525 1200)(-825 1200);
FORCEPROP 2 LAST SIG_NAME SMB_RT_CPU1_P1_R_SCL
J 0
(-1610 1210);
DISPLAY 0.680851 (-1610 1210);
PAINT SKYBLUE (-1610 1210);
WIRE 16 -1 (-2525 1025)(-825 1025);
FORCEPROP 2 LAST SIG_NAME SMB_RT_CPU1_P3_R_SCL
J 0
(-1660 1035);
DISPLAY 0.680851 (-1660 1035);
WIRE 16 -1 (-2525 1100)(-825 1100);
FORCEPROP 2 LAST SIG_NAME SMB_RT_CPU1_P3_R_SDA
J 0
(-1635 1110);
DISPLAY 0.680851 (-1635 1110);
WIRE 16 -1 (-2525 950)(-825 950);
FORCEPROP 2 LAST SIG_NAME SMB_RT_CPU1_P2_R_SDA
J 0
(-1610 960);
DISPLAY 0.680851 (-1610 960);
WIRE 16 -1 (-2525 875)(-825 875);
FORCEPROP 2 LAST SIG_NAME SMB_RT_CPU1_P2_R_SCL
J 0
(-1635 885);
DISPLAY 0.680851 (-1635 885);
WIRE 16 -1 (-5850 1525)(-4150 1525);
FORCEPROP 2 LAST SIG_NAME SMB_RT_CPU0_P0_R_SDA
J 0
(-4910 1535);
DISPLAY 0.680851 (-4910 1535);
PAINT SKYBLUE (-4910 1535);
WIRE 16 -1 (-5850 1425)(-4150 1425);
FORCEPROP 2 LAST SIG_NAME SMB_RT_CPU0_P0_R_SCL
J 0
(-4935 1435);
DISPLAY 0.680851 (-4935 1435);
PAINT SKYBLUE (-4935 1435);
WIRE 16 -1 (-5850 1275)(-4150 1275);
FORCEPROP 2 LAST SIG_NAME SMB_RT_CPU0_P1_R_SCL
J 0
(-4935 1285);
DISPLAY 0.680851 (-4935 1285);
PAINT SKYBLUE (-4935 1285);
WIRE 16 -1 (-5850 1175)(-4150 1175);
FORCEPROP 2 LAST SIG_NAME SMB_RT_CPU0_P3_R_SDA
J 0
(-4960 1185);
DISPLAY 0.680851 (-4960 1185);
WIRE 16 -1 (-5850 1100)(-4150 1100);
FORCEPROP 2 LAST SIG_NAME SMB_RT_CPU0_P3_R_SCL
J 0
(-4985 1110);
DISPLAY 0.680851 (-4985 1110);
WIRE 16 -1 (-5850 1025)(-4150 1025);
FORCEPROP 2 LAST SIG_NAME SMB_RT_CPU0_P2_R_SDA
J 0
(-4935 1035);
DISPLAY 0.680851 (-4935 1035);
WIRE 16 -1 (-5850 950)(-4150 950);
FORCEPROP 2 LAST SIG_NAME SMB_RT_CPU0_P2_R_SCL
J 0
(-4960 960);
DISPLAY 0.680851 (-4960 960);
WIRE 16 -1 (-7100 1475)(-8600 1475);
FORCEPROP 2 LAST SIG_NAME RT_SMB_MUX_ADDR2
J 0
(-7885 1510);
DISPLAY 0.680851 (-7885 1510);
WIRE 16 -1 (-8600 1700)(-8600 1475);
WIRE 16 -1 (-8600 1475)(-8600 1125);
WIRE 16 -1 (-7950 1125)(-7950 1275);
WIRE 16 -1 (-7100 1275)(-7950 1275);
FORCEPROP 2 LAST SIG_NAME RT_SMB_MUX_ADDR0
J 0
(-7885 1285);
DISPLAY 0.680851 (-7885 1285);
WIRE 16 -1 (-7950 1275)(-7950 1675);
WIRE 16 -1 (-8300 1125)(-8300 1375);
WIRE 16 -1 (-7100 1375)(-8300 1375);
FORCEPROP 2 LAST SIG_NAME RT_SMB_MUX_ADDR1
J 0
(-7885 1385);
DISPLAY 0.680851 (-7885 1385);
WIRE 16 -1 (-8300 1375)(-8300 1700);
WIRE 16 -1 (-6450 4600)(-7675 4600);
FORCEPROP 2 LAST SIG_NAME SMB_RT_CPU1_P0_R_SDA
J 0
(-7610 4610);
DISPLAY 0.680851 (-7610 4610);
PAINT SKYBLUE (-7610 4610);
WIRE 16 -1 (-5250 4350)(-6250 4350);
FORCEPROP 2 LAST SIG_NAME SMB_RT_CPU1_P3_SCL
J 0
(-5985 4360);
DISPLAY 0.680851 (-5985 4360);
PAINT SKYBLUE (-5985 4360);
FORCEPROP 2 LASTPROP $XRERR UNIQUE?
J 0
(-6225 4360);
DISPLAY 0.638298 (-6225 4360);
PAINT MONO (-6225 4360);
DISPLAY INVISIBLE (-6225 4360);
WIRE 16 -1 (-5850 1350)(-4150 1350);
FORCEPROP 2 LAST SIG_NAME SMB_RT_CPU0_P1_R_SDA
J 0
(-4935 1360);
DISPLAY 0.680851 (-4935 1360);
PAINT SKYBLUE (-4935 1360);
WIRE 16 -1 (-6450 4550)(-7700 4550);
FORCEPROP 2 LAST SIG_NAME SMB_RT_CPU1_P0_R_SCL
J 0
(-7610 4560);
DISPLAY 0.680851 (-7610 4560);
PAINT SKYBLUE (-7610 4560);
WIRE 16 -1 (-6450 4500)(-7675 4500);
FORCEPROP 2 LAST SIG_NAME SMB_RT_CPU1_P1_R_SDA
J 0
(-7610 4510);
DISPLAY 0.680851 (-7610 4510);
PAINT SKYBLUE (-7610 4510);
WIRE 16 -1 (-5250 4300)(-6250 4300);
FORCEPROP 2 LAST SIG_NAME SMB_RT_CPU1_P2_SDA
J 0
(-5985 4310);
DISPLAY 0.680851 (-5985 4310);
PAINT SKYBLUE (-5985 4310);
FORCEPROP 2 LASTPROP $XRERR UNIQUE?
J 0
(-6225 4310);
DISPLAY 0.638298 (-6225 4310);
PAINT MONO (-6225 4310);
DISPLAY INVISIBLE (-6225 4310);
WIRE 16 -1 (-5250 4250)(-6250 4250);
FORCEPROP 2 LAST SIG_NAME SMB_RT_CPU1_P2_SCL
J 0
(-5985 4260);
DISPLAY 0.680851 (-5985 4260);
PAINT SKYBLUE (-5985 4260);
FORCEPROP 2 LASTPROP $XRERR UNIQUE?
J 0
(-6225 4260);
DISPLAY 0.638298 (-6225 4260);
PAINT MONO (-6225 4260);
DISPLAY INVISIBLE (-6225 4260);
WIRE 16 -1 (-5250 4600)(-6250 4600);
FORCEPROP 2 LAST SIG_NAME SMB_RT_CPU1_P0_SDA
J 0
(-5985 4610);
DISPLAY 0.680851 (-5985 4610);
PAINT SKYBLUE (-5985 4610);
FORCEPROP 2 LASTPROP $XRERR UNIQUE?
J 0
(-6225 4610);
DISPLAY 0.638298 (-6225 4610);
PAINT MONO (-6225 4610);
DISPLAY INVISIBLE (-6225 4610);
WIRE 16 -1 (-6450 4300)(-7675 4300);
FORCEPROP 2 LAST SIG_NAME SMB_RT_CPU1_P2_R_SDA
J 0
(-7610 4310);
DISPLAY 0.680851 (-7610 4310);
WIRE 16 -1 (-6800 4700)(-8150 4700);
FORCEPROP 2 LAST SIG_NAME RST_SMB_RT_R1_N
J 0
(-7885 4710);
DISPLAY 0.680851 (-7885 4710);
WIRE 16 -1 (-3200 4400)(-4550 4400);
FORCEPROP 2 LAST SIG_NAME SMB_RT_CPU0_P3_SDA
J 0
(-4285 4410);
DISPLAY 0.680851 (-4285 4410);
FORCEPROP 2 LASTPROP $XRERR UNIQUE?
J 0
(-4525 4410);
DISPLAY 0.638298 (-4525 4410);
PAINT MONO (-4525 4410);
DISPLAY INVISIBLE (-4525 4410);
WIRE 16 -1 (-3200 4450)(-4550 4450);
FORCEPROP 2 LAST SIG_NAME SMB_RT_CPU0_P1_SCL
J 0
(-4285 4460);
DISPLAY 0.680851 (-4285 4460);
FORCEPROP 2 LASTPROP $XRERR UNIQUE?
J 0
(-4525 4460);
DISPLAY 0.638298 (-4525 4460);
PAINT MONO (-4525 4460);
DISPLAY INVISIBLE (-4525 4460);
WIRE 16 -1 (-5250 4500)(-6250 4500);
FORCEPROP 2 LAST SIG_NAME SMB_RT_CPU1_P1_SDA
J 0
(-5985 4510);
DISPLAY 0.680851 (-5985 4510);
PAINT SKYBLUE (-5985 4510);
FORCEPROP 2 LASTPROP $XRERR UNIQUE?
J 0
(-6225 4510);
DISPLAY 0.638298 (-6225 4510);
PAINT MONO (-6225 4510);
DISPLAY INVISIBLE (-6225 4510);
WIRE 16 -1 (-5250 4550)(-6250 4550);
FORCEPROP 2 LAST SIG_NAME SMB_RT_CPU1_P0_SCL
J 0
(-5985 4560);
DISPLAY 0.680851 (-5985 4560);
PAINT SKYBLUE (-5985 4560);
FORCEPROP 2 LASTPROP $XRERR UNIQUE?
J 0
(-6225 4560);
DISPLAY 0.638298 (-6225 4560);
PAINT MONO (-6225 4560);
DISPLAY INVISIBLE (-6225 4560);
WIRE 16 -1 (-5250 4400)(-6250 4400);
FORCEPROP 2 LAST SIG_NAME SMB_RT_CPU1_P3_SDA
J 0
(-5985 4410);
DISPLAY 0.680851 (-5985 4410);
PAINT SKYBLUE (-5985 4410);
FORCEPROP 2 LASTPROP $XRERR UNIQUE?
J 0
(-6225 4410);
DISPLAY 0.638298 (-6225 4410);
PAINT MONO (-6225 4410);
DISPLAY INVISIBLE (-6225 4410);
WIRE 16 -1 (-5250 4450)(-6250 4450);
FORCEPROP 2 LAST SIG_NAME SMB_RT_CPU1_P1_SCL
J 0
(-5985 4460);
DISPLAY 0.680851 (-5985 4460);
PAINT SKYBLUE (-5985 4460);
FORCEPROP 2 LASTPROP $XRERR UNIQUE?
J 0
(-6225 4460);
DISPLAY 0.638298 (-6225 4460);
PAINT MONO (-6225 4460);
DISPLAY INVISIBLE (-6225 4460);
WIRE 16 -1 (-3200 4350)(-4550 4350);
FORCEPROP 2 LAST SIG_NAME SMB_RT_CPU0_P3_SCL
J 0
(-4285 4360);
DISPLAY 0.680851 (-4285 4360);
FORCEPROP 2 LASTPROP $XRERR UNIQUE?
J 0
(-4525 4360);
DISPLAY 0.638298 (-4525 4360);
PAINT MONO (-4525 4360);
DISPLAY INVISIBLE (-4525 4360);
WIRE 16 -1 (-3200 4300)(-4550 4300);
FORCEPROP 2 LAST SIG_NAME SMB_RT_CPU0_P2_SDA
J 0
(-4285 4310);
DISPLAY 0.680851 (-4285 4310);
FORCEPROP 2 LASTPROP $XRERR UNIQUE?
J 0
(-4525 4310);
DISPLAY 0.638298 (-4525 4310);
PAINT MONO (-4525 4310);
DISPLAY INVISIBLE (-4525 4310);
WIRE 16 -1 (-3200 4250)(-4550 4250);
FORCEPROP 2 LAST SIG_NAME SMB_RT_CPU0_P2_SCL
J 0
(-4285 4260);
DISPLAY 0.680851 (-4285 4260);
FORCEPROP 2 LASTPROP $XRERR UNIQUE?
J 0
(-4525 4260);
DISPLAY 0.638298 (-4525 4260);
PAINT MONO (-4525 4260);
DISPLAY INVISIBLE (-4525 4260);
WIRE 16 -1 (-5250 4900)(-6200 4900);
FORCEPROP 2 LAST SIG_NAME RT_SMB_MUX_ADDR0
J 0
(-6085 4910);
DISPLAY 0.680851 (-6085 4910);
WIRE 16 -1 (-5250 4850)(-6200 4850);
FORCEPROP 2 LAST SIG_NAME RT_SMB_MUX_ADDR1
J 0
(-6085 4860);
DISPLAY 0.680851 (-6085 4860);
WIRE 16 -1 (-5250 4700)(-6600 4700);
FORCEPROP 2 LAST SIG_NAME RST_SMB_RT_N
J 0
(-6085 4710);
DISPLAY 0.680851 (-6085 4710);
FORCEPROP 2 LASTPROP $XRERR UNIQUE?
J 0
(-6325 4710);
DISPLAY 0.638298 (-6325 4710);
PAINT MONO (-6325 4710);
DISPLAY INVISIBLE (-6325 4710);
WIRE 16 -1 (-5250 4800)(-6200 4800);
FORCEPROP 2 LAST SIG_NAME RT_SMB_MUX_ADDR2
J 0
(-6085 4810);
DISPLAY 0.680851 (-6085 4810);
DOT 1 (-8600 750);
DOT 1 (-8300 750);
DOT 1 (-8600 1475);
DOT 1 (-8300 1375);
DOT 1 (-8600 2125);
DOT 1 (-8300 2125);
DOT 1 (-6475 1025);
DOT 1 (-6475 1100);
DOT 1 (-7950 1275);
DOT 1 (-6475 1175);
DOT 1 (-6475 1350);
DOT 1 (-6475 1275);
DOT 1 (-6475 1525);
DOT 1 (-6475 1425);
DOT 1 (-3150 950);
DOT 1 (-3150 1025);
DOT 1 (-3150 1100);
DOT 1 (-3150 1200);
DOT 1 (-3150 1275);
DOT 1 (-3150 1350);
DOT 1 (-3150 1450);
DOT 1 (-5475 5525);
DOT 1 (-2675 4800);
DOT 1 (-2575 4850);
FORCENOTE
TCA9548 ADDR: 0XE0 (8-BIT) /0X70 (7-BIT)
(-6500 3650) 0;
DISPLAY LEFT (-6500 3650);
DISPLAY 1.595745 (-6500 3650);
QUIT
